FILE_TYPE = MACRO_DRAWING;
SET COLOR_WIRE YELLOW;
SET COLOR_PROP MONO;
SET COLOR_DOT WHITE;
SET COLOR_ARC YELLOW;
SET COLOR_BODY GREEN;
SET COLOR_NOTE MONO;
SET PROP_DISPLAY VALUE;
SET PAGE_NUMBER P111;
FORCEADD CAP_A..1
R 1
(2750 1900);
FORCEPROP 1 LAST PACK_TYPE 0402V
J 0
(3000 1950);
DISPLAY 0.617021 (3000 1950);
PAINT SKYBLUE (3000 1950);
FORCEPROP 1 LASTPIN (2650 1900) $PN 1
J 0
(2670 1910);
DISPLAY 0.617021 (2670 1910);
PAINT WHITE (2670 1910);
FORCEPROP 1 LASTPIN (2850 1900) $PN 2
J 0
(2795 1910);
DISPLAY 0.617021 (2795 1910);
PAINT WHITE (2795 1910);
FORCEPROP 1 LAST MATERIAL X7R
J 0
(2900 1950);
DISPLAY 0.617021 (2900 1950);
PAINT SKYBLUE (2900 1950);
FORCEPROP 1 LAST PART_NUMBER A36096-030
J 0
(2650 1825);
DISPLAY 0.617021 (2650 1825);
PAINT BLUE (2650 1825);
FORCEPROP 1 LAST VOLTAGE 16V
J 0
(2650 1950);
DISPLAY 0.617021 (2650 1950);
PAINT SKYBLUE (2650 1950);
FORCEPROP 1 LAST TOLERANCE 10%
J 0
(2775 1950);
DISPLAY 0.617021 (2775 1950);
PAINT SKYBLUE (2775 1950);
FORCEPROP 1 LAST LOCATION C9A2
J 0
(2675 2000);
DISPLAY 0.617021 (2675 2000);
PAINT AQUA (2675 2000);
FORCEPROP 1 LAST VALUE 0.1UF
J 0
(2500 1950);
DISPLAY 0.617021 (2500 1950);
PAINT SKYBLUE (2500 1950);
FORCEPROP 1 LAST PATH I10
R 1
J 0
(2600 1950);
DISPLAY 0.978723 (2600 1950);
PAINT WHITE (2600 1950);
DISPLAY INVISIBLE (2600 1950);
FORCEPROP 2 LAST SEC_TYPE 0402V
R 1
J 0
(2750 2025);
DISPLAY 1.659574 (2750 2025);
PAINT ORANGE (2750 2025);
DISPLAY INVISIBLE (2750 2025);
FORCEPROP 2 LAST CDS_LIB dev_discrete
J 0
(2750 1900);
PAINT ORANGE (2750 1900);
DISPLAY INVISIBLE (2750 1900);
FORCEPROP 2 LAST CDS_LOCATION C9A2
J 0
(2750 1975);
DISPLAY 0.617021 (2750 1975);
PAINT AQUA (2750 1975);
DISPLAY INVISIBLE (2750 1975);
FORCEPROP 2 LAST CDS_SEC 1
R 1
J 0
(2750 2025);
PAINT ORANGE (2750 2025);
DISPLAY INVISIBLE (2750 2025);
FORCEPROP 2 LAST ROOM DEBUG
J 0
(2750 2025);
DISPLAY 1.617021 (2750 2025);
PAINT WHITE (2750 2025);
DISPLAY INVISIBLE (2750 2025);
FORCEPROP 2 LAST BOM_COST DEBUG
J 0
(2750 2025);
DISPLAY 1.617021 (2750 2025);
PAINT WHITE (2750 2025);
DISPLAY INVISIBLE (2750 2025);
FORCEPROP 2 LAST SEC 1
J 0
(2750 2025);
DISPLAY 1.510638 (2750 2025);
PAINT MONO (2750 2025);
DISPLAY INVISIBLE (2750 2025);
FORCEADD RES..1
(2725 1700);
FORCEPROP 1 LAST MATERIAL CHIP
J 0
(3000 1650);
DISPLAY 0.617021 (3000 1650);
PAINT SKYBLUE (3000 1650);
FORCEPROP 1 LAST PACK_TYPE 0402
J 0
(2875 1650);
DISPLAY 0.617021 (2875 1650);
PAINT SKYBLUE (2875 1650);
FORCEPROP 1 LAST LOCATION R9A14
J 0
(2675 1750);
DISPLAY 0.617021 (2675 1750);
PAINT AQUA (2675 1750);
FORCEPROP 1 LASTPIN (2825 1700) $PN 2
J 0
(2787 1712);
DISPLAY 0.617021 (2787 1712);
PAINT WHITE (2787 1712);
FORCEPROP 1 LAST VALUE 1.00K
J 2
(2575 1650);
DISPLAY 0.617021 (2575 1650);
PAINT SKYBLUE (2575 1650);
FORCEPROP 1 LASTPIN (2625 1700) $PN 1
J 0
(2637 1712);
DISPLAY 0.617021 (2637 1712);
PAINT WHITE (2637 1712);
FORCEPROP 1 LAST WATTAGE 1/16W
J 2
(2725 1650);
DISPLAY 0.617021 (2725 1650);
PAINT SKYBLUE (2725 1650);
FORCEPROP 1 LAST TOLERANCE 1%
J 0
(2775 1650);
DISPLAY 0.617021 (2775 1650);
PAINT SKYBLUE (2775 1650);
FORCEPROP 1 LAST PART_NUMBER G21796-026
J 0
(2850 1725);
DISPLAY 0.617021 (2850 1725);
PAINT BLUE (2850 1725);
FORCEPROP 2 LAST CDS_LOCATION R9A14
J 0
(2675 1750);
DISPLAY 0.617021 (2675 1750);
PAINT AQUA (2675 1750);
DISPLAY INVISIBLE (2675 1750);
FORCEPROP 2 LAST CDS_LIB mstr_discrete
J 0
(2725 1700);
DISPLAY 2.212766 (2725 1700);
PAINT ORANGE (2725 1700);
DISPLAY INVISIBLE (2725 1700);
FORCEPROP 1 LAST PATH I11
J 0
(2675 1850);
DISPLAY 0.978723 (2675 1850);
PAINT WHITE (2675 1850);
DISPLAY INVISIBLE (2675 1850);
FORCEPROP 2 LAST SEC 1
J 0
(2675 1900);
DISPLAY 1.510638 (2675 1900);
PAINT MONO (2675 1900);
DISPLAY INVISIBLE (2675 1900);
FORCEPROP 2 LAST BOM_COST DEBUG
J 0
(2675 1800);
DISPLAY 1.617021 (2675 1800);
PAINT WHITE (2675 1800);
DISPLAY INVISIBLE (2675 1800);
FORCEPROP 2 LAST SEC_TYPE 0402
J 0
(2675 1800);
DISPLAY 1.659574 (2675 1800);
PAINT ORANGE (2675 1800);
DISPLAY INVISIBLE (2675 1800);
FORCEPROP 2 LAST ROOM DEBUG
J 0
(2675 1850);
DISPLAY 1.617021 (2675 1850);
PAINT WHITE (2675 1850);
DISPLAY INVISIBLE (2675 1850);
FORCEADD CAP_A..1
R 1
(2800 1450);
FORCEPROP 1 LAST VOLTAGE 16V
J 0
(2550 1475);
DISPLAY 0.617021 (2550 1475);
PAINT SKYBLUE (2550 1475);
FORCEPROP 1 LASTPIN (2700 1450) $PN 1
J 0
(2720 1460);
DISPLAY 0.617021 (2720 1460);
PAINT WHITE (2720 1460);
FORCEPROP 1 LASTPIN (2900 1450) $PN 2
J 0
(2845 1460);
DISPLAY 0.617021 (2845 1460);
PAINT WHITE (2845 1460);
FORCEPROP 1 LAST MATERIAL X7R
J 0
(3050 1475);
DISPLAY 0.617021 (3050 1475);
PAINT SKYBLUE (3050 1475);
FORCEPROP 1 LAST VALUE 0.1UF
J 0
(2450 1475);
DISPLAY 0.617021 (2450 1475);
PAINT SKYBLUE (2450 1475);
FORCEPROP 1 LAST PART_NUMBER A36096-030
J 0
(2675 1350);
DISPLAY 0.617021 (2675 1350);
PAINT BLUE (2675 1350);
FORCEPROP 1 LAST TOLERANCE 10%
J 0
(2625 1475);
DISPLAY 0.617021 (2625 1475);
PAINT SKYBLUE (2625 1475);
FORCEPROP 1 LAST LOCATION C9A5
J 0
(2725 1525);
DISPLAY 0.617021 (2725 1525);
PAINT AQUA (2725 1525);
FORCEPROP 1 LAST PACK_TYPE 0402V
J 0
(2900 1475);
DISPLAY 0.617021 (2900 1475);
PAINT SKYBLUE (2900 1475);
FORCEPROP 1 LAST PATH I12
R 1
J 0
(2650 1500);
DISPLAY 0.978723 (2650 1500);
PAINT WHITE (2650 1500);
DISPLAY INVISIBLE (2650 1500);
FORCEPROP 2 LAST CDS_LIB dev_discrete
J 0
(2800 1450);
PAINT ORANGE (2800 1450);
DISPLAY INVISIBLE (2800 1450);
FORCEPROP 2 LAST CDS_LOCATION C9A5
J 0
(2800 1525);
DISPLAY 0.617021 (2800 1525);
PAINT AQUA (2800 1525);
DISPLAY INVISIBLE (2800 1525);
FORCEPROP 2 LAST SEC 1
J 0
(2800 1575);
DISPLAY 1.510638 (2800 1575);
PAINT MONO (2800 1575);
DISPLAY INVISIBLE (2800 1575);
FORCEPROP 2 LAST SEC_TYPE 0402V
R 1
J 0
(2800 1575);
DISPLAY 1.659574 (2800 1575);
PAINT ORANGE (2800 1575);
DISPLAY INVISIBLE (2800 1575);
FORCEPROP 2 LAST CDS_SEC 1
R 1
J 0
(2800 1575);
PAINT ORANGE (2800 1575);
DISPLAY INVISIBLE (2800 1575);
FORCEPROP 2 LAST BOM_COST DEBUG
J 0
(2800 1575);
DISPLAY 1.617021 (2800 1575);
PAINT WHITE (2800 1575);
DISPLAY INVISIBLE (2800 1575);
FORCEPROP 2 LAST ROOM DEBUG
J 0
(2800 1575);
DISPLAY 1.617021 (2800 1575);
PAINT WHITE (2800 1575);
DISPLAY INVISIBLE (2800 1575);
FORCEADD RES..1
(2725 1150);
FORCEPROP 1 LAST MATERIAL CHIP
J 0
(2975 1100);
DISPLAY 0.617021 (2975 1100);
PAINT SKYBLUE (2975 1100);
FORCEPROP 1 LAST TOLERANCE 1%
J 0
(2725 1100);
DISPLAY 0.617021 (2725 1100);
PAINT SKYBLUE (2725 1100);
FORCEPROP 1 LAST WATTAGE 1/16W
J 2
(2700 1100);
DISPLAY 0.617021 (2700 1100);
PAINT SKYBLUE (2700 1100);
FORCEPROP 1 LAST VALUE 1.00K
J 2
(2575 1100);
DISPLAY 0.617021 (2575 1100);
PAINT SKYBLUE (2575 1100);
FORCEPROP 1 LASTPIN (2625 1150) $PN 1
J 0
(2637 1162);
DISPLAY 0.617021 (2637 1162);
PAINT WHITE (2637 1162);
FORCEPROP 1 LAST LOCATION R1L23
J 0
(2650 1225);
DISPLAY 0.617021 (2650 1225);
PAINT AQUA (2650 1225);
FORCEPROP 1 LAST PACK_TYPE 0402
J 0
(2850 1100);
DISPLAY 0.617021 (2850 1100);
PAINT SKYBLUE (2850 1100);
FORCEPROP 1 LAST PART_NUMBER G21796-026
J 0
(2850 1175);
DISPLAY 0.617021 (2850 1175);
PAINT BLUE (2850 1175);
FORCEPROP 1 LASTPIN (2825 1150) $PN 2
J 0
(2787 1162);
DISPLAY 0.617021 (2787 1162);
PAINT WHITE (2787 1162);
FORCEPROP 2 LAST SEC 1
J 0
(2675 1350);
DISPLAY 1.510638 (2675 1350);
PAINT MONO (2675 1350);
DISPLAY INVISIBLE (2675 1350);
FORCEPROP 1 LAST PATH I13
J 0
(2675 1300);
DISPLAY 0.978723 (2675 1300);
PAINT WHITE (2675 1300);
DISPLAY INVISIBLE (2675 1300);
FORCEPROP 2 LAST SEC_TYPE 0402
J 0
(2650 1275);
DISPLAY 1.659574 (2650 1275);
PAINT ORANGE (2650 1275);
DISPLAY INVISIBLE (2650 1275);
FORCEPROP 2 LAST BOM_COST DEBUG
J 0
(2650 1275);
DISPLAY 1.617021 (2650 1275);
PAINT WHITE (2650 1275);
DISPLAY INVISIBLE (2650 1275);
FORCEPROP 2 LAST ROOM DEBUG
J 0
(2675 1300);
DISPLAY 1.617021 (2675 1300);
PAINT WHITE (2675 1300);
DISPLAY INVISIBLE (2675 1300);
FORCEPROP 2 LAST CDS_LOCATION R1L23
J 0
(2650 1225);
DISPLAY 0.617021 (2650 1225);
PAINT AQUA (2650 1225);
DISPLAY INVISIBLE (2650 1225);
FORCEPROP 2 LAST CDS_LIB mstr_discrete
J 0
(2725 1150);
DISPLAY 2.212766 (2725 1150);
PAINT ORANGE (2725 1150);
DISPLAY INVISIBLE (2725 1150);
FORCEADD CAP_A..1
R 1
(2825 950);
FORCEPROP 1 LAST PACK_TYPE 0402V
J 0
(3025 975);
DISPLAY 0.617021 (3025 975);
PAINT SKYBLUE (3025 975);
FORCEPROP 1 LASTPIN (2925 950) $PN 2
J 0
(2870 960);
DISPLAY 0.617021 (2870 960);
PAINT WHITE (2870 960);
FORCEPROP 1 LAST MATERIAL X7R
J 0
(2925 975);
DISPLAY 0.617021 (2925 975);
PAINT SKYBLUE (2925 975);
FORCEPROP 1 LAST VALUE 0.1UF
J 0
(2475 975);
DISPLAY 0.617021 (2475 975);
PAINT SKYBLUE (2475 975);
FORCEPROP 1 LAST VOLTAGE 16V
J 0
(2600 975);
DISPLAY 0.617021 (2600 975);
PAINT SKYBLUE (2600 975);
FORCEPROP 1 LAST PART_NUMBER A36096-030
J 0
(2650 850);
DISPLAY 0.617021 (2650 850);
PAINT BLUE (2650 850);
FORCEPROP 1 LASTPIN (2725 950) $PN 1
J 0
(2745 960);
DISPLAY 0.617021 (2745 960);
PAINT WHITE (2745 960);
FORCEPROP 1 LAST TOLERANCE 10%
J 0
(2675 975);
DISPLAY 0.617021 (2675 975);
PAINT SKYBLUE (2675 975);
FORCEPROP 1 LAST LOCATION C1L8
J 0
(2775 1025);
DISPLAY 0.617021 (2775 1025);
PAINT AQUA (2775 1025);
FORCEPROP 2 LAST SEC 1
J 0
(2825 1075);
DISPLAY 1.510638 (2825 1075);
PAINT MONO (2825 1075);
DISPLAY INVISIBLE (2825 1075);
FORCEPROP 2 LAST BOM_COST DEBUG
J 0
(2825 1075);
DISPLAY 1.617021 (2825 1075);
PAINT WHITE (2825 1075);
DISPLAY INVISIBLE (2825 1075);
FORCEPROP 2 LAST ROOM DEBUG
J 0
(2825 1075);
DISPLAY 1.617021 (2825 1075);
PAINT WHITE (2825 1075);
DISPLAY INVISIBLE (2825 1075);
FORCEPROP 2 LAST SEC_TYPE 0402V
R 1
J 0
(2825 1075);
DISPLAY 1.659574 (2825 1075);
PAINT ORANGE (2825 1075);
DISPLAY INVISIBLE (2825 1075);
FORCEPROP 2 LAST CDS_SEC 1
R 1
J 0
(2825 1075);
PAINT ORANGE (2825 1075);
DISPLAY INVISIBLE (2825 1075);
FORCEPROP 2 LAST CDS_LOCATION C1L8
J 0
(2825 1025);
DISPLAY 0.617021 (2825 1025);
PAINT AQUA (2825 1025);
DISPLAY INVISIBLE (2825 1025);
FORCEPROP 2 LAST CDS_LIB dev_discrete
J 0
(2825 950);
PAINT ORANGE (2825 950);
DISPLAY INVISIBLE (2825 950);
FORCEPROP 1 LAST PATH I14
R 1
J 0
(2675 1000);
DISPLAY 0.978723 (2675 1000);
PAINT WHITE (2675 1000);
DISPLAY INVISIBLE (2675 1000);
FORCEADD OFFPAGE..4
(1875 3700);
FORCEPROP 2 LAST $XR0 114 
J 0
(2061 3700);
DISPLAY 0.638298 (2061 3700);
PAINT MONO (2061 3700);
FORCEPROP 2 LAST CDS_LIB mstr_standard
J 0
(1875 3700);
DISPLAY 2.212766 (1875 3700);
PAINT ORANGE (1875 3700);
DISPLAY INVISIBLE (1875 3700);
FORCEPROP 2 LAST PATH I15
J 0
(2075 3750);
DISPLAY 1.021277 (2075 3750);
PAINT ORANGE (2075 3750);
DISPLAY INVISIBLE (2075 3750);
FORCEPROP 2 LAST ROOM CPU_XDP_DEBUG
J 0
(2200 3750);
DISPLAY 1.617021 (2200 3750);
PAINT WHITE (2200 3750);
DISPLAY INVISIBLE (2200 3750);
FORCEPROP 2 LAST BOM_COST DEBUG
J 0
(2200 3750);
DISPLAY 1.617021 (2200 3750);
PAINT WHITE (2200 3750);
DISPLAY INVISIBLE (2200 3750);
FORCEPROP 1 LAST OFFPAGE TRUE
J 0
(2200 3575);
PAINT GREEN (2200 3575);
DISPLAY INVISIBLE (2200 3575);
FORCEPROP 1 LAST COMMENT_BODY TRUE
J 0
(1850 3600);
DISPLAY 1.893617 (1850 3600);
PAINT PEACH (1850 3600);
DISPLAY INVISIBLE (1850 3600);
FORCEADD OFFPAGE..4
(1875 3650);
FORCEPROP 2 LAST $XR0 114 
J 0
(2061 3650);
DISPLAY 0.638298 (2061 3650);
PAINT MONO (2061 3650);
FORCEPROP 2 LAST CDS_LIB mstr_standard
J 0
(1875 3650);
DISPLAY 2.212766 (1875 3650);
PAINT ORANGE (1875 3650);
DISPLAY INVISIBLE (1875 3650);
FORCEPROP 2 LAST PATH I16
J 0
(2075 3700);
DISPLAY 1.021277 (2075 3700);
PAINT ORANGE (2075 3700);
DISPLAY INVISIBLE (2075 3700);
FORCEPROP 2 LAST ROOM CPU_XDP_DEBUG
J 0
(2200 3700);
DISPLAY 1.617021 (2200 3700);
PAINT WHITE (2200 3700);
DISPLAY INVISIBLE (2200 3700);
FORCEPROP 2 LAST BOM_COST DEBUG
J 0
(2200 3700);
DISPLAY 1.617021 (2200 3700);
PAINT WHITE (2200 3700);
DISPLAY INVISIBLE (2200 3700);
FORCEPROP 1 LAST OFFPAGE TRUE
J 0
(2200 3525);
PAINT GREEN (2200 3525);
DISPLAY INVISIBLE (2200 3525);
FORCEPROP 1 LAST COMMENT_BODY TRUE
J 0
(1850 3550);
DISPLAY 1.893617 (1850 3550);
PAINT PEACH (1850 3550);
DISPLAY INVISIBLE (1850 3550);
FORCEADD OFFPAGE..4
(1875 3550);
FORCEPROP 2 LAST $XR1 118 
J 0
(2181 3550);
DISPLAY 0.638298 (2181 3550);
PAINT MONO (2181 3550);
FORCEPROP 2 LAST $XR0 111 
J 0
(2061 3550);
DISPLAY 0.638298 (2061 3550);
PAINT MONO (2061 3550);
FORCEPROP 2 LAST CDS_LIB mstr_standard
J 0
(1875 3550);
DISPLAY 2.212766 (1875 3550);
PAINT ORANGE (1875 3550);
DISPLAY INVISIBLE (1875 3550);
FORCEPROP 2 LAST PATH I17
J 0
(2075 3600);
DISPLAY 1.021277 (2075 3600);
PAINT ORANGE (2075 3600);
DISPLAY INVISIBLE (2075 3600);
FORCEPROP 2 LAST ROOM CPU_XDP_DEBUG
J 0
(2175 3600);
DISPLAY 1.617021 (2175 3600);
PAINT WHITE (2175 3600);
DISPLAY INVISIBLE (2175 3600);
FORCEPROP 2 LAST BOM_COST DEBUG
J 0
(2175 3600);
DISPLAY 1.617021 (2175 3600);
PAINT WHITE (2175 3600);
DISPLAY INVISIBLE (2175 3600);
FORCEPROP 1 LAST OFFPAGE TRUE
J 0
(2200 3425);
PAINT GREEN (2200 3425);
DISPLAY INVISIBLE (2200 3425);
FORCEPROP 1 LAST COMMENT_BODY TRUE
J 0
(1850 3450);
DISPLAY 1.893617 (1850 3450);
PAINT PEACH (1850 3450);
DISPLAY INVISIBLE (1850 3450);
FORCEADD OFFPAGE..4
(1875 3400);
FORCEPROP 2 LAST $XR2 255 
J 0
(2301 3400);
DISPLAY 0.638298 (2301 3400);
PAINT MONO (2301 3400);
FORCEPROP 2 LAST $XR1 118 
J 0
(2181 3400);
DISPLAY 0.638298 (2181 3400);
PAINT MONO (2181 3400);
FORCEPROP 2 LAST $XR0 112 
J 0
(2061 3400);
DISPLAY 0.638298 (2061 3400);
PAINT MONO (2061 3400);
FORCEPROP 2 LAST CDS_LIB mstr_standard
J 0
(1875 3400);
DISPLAY 2.212766 (1875 3400);
PAINT ORANGE (1875 3400);
DISPLAY INVISIBLE (1875 3400);
FORCEPROP 2 LAST PATH I18
J 0
(2200 3450);
DISPLAY 1.021277 (2200 3450);
PAINT ORANGE (2200 3450);
DISPLAY INVISIBLE (2200 3450);
FORCEPROP 2 LAST ROOM CPU_XDP_DEBUG
J 0
(2075 3450);
DISPLAY 1.617021 (2075 3450);
PAINT WHITE (2075 3450);
DISPLAY INVISIBLE (2075 3450);
FORCEPROP 2 LAST BOM_COST DEBUG
J 0
(2075 3450);
DISPLAY 1.617021 (2075 3450);
PAINT WHITE (2075 3450);
DISPLAY INVISIBLE (2075 3450);
FORCEPROP 1 LAST OFFPAGE TRUE
J 0
(2200 3275);
PAINT GREEN (2200 3275);
DISPLAY INVISIBLE (2200 3275);
FORCEPROP 1 LAST COMMENT_BODY TRUE
J 0
(1850 3300);
DISPLAY 1.893617 (1850 3300);
PAINT PEACH (1850 3300);
DISPLAY INVISIBLE (1850 3300);
FORCEADD OFFPAGE..2
(1875 3300);
FORCEPROP 2 LAST $XR2 112 
J 0
(2304 3300);
DISPLAY 0.638298 (2304 3300);
PAINT MONO (2304 3300);
FORCEPROP 2 LAST $XR1 254 
J 0
(2184 3300);
DISPLAY 0.638298 (2184 3300);
PAINT MONO (2184 3300);
FORCEPROP 2 LAST $XR0 118 
J 0
(2064 3300);
DISPLAY 0.638298 (2064 3300);
PAINT MONO (2064 3300);
FORCEPROP 2 LAST CDS_LIB mstr_standard
J 0
(1875 3300);
DISPLAY 2.212766 (1875 3300);
PAINT ORANGE (1875 3300);
DISPLAY INVISIBLE (1875 3300);
FORCEPROP 2 LAST PATH I19
J 0
(2200 3350);
DISPLAY 1.021277 (2200 3350);
PAINT ORANGE (2200 3350);
DISPLAY INVISIBLE (2200 3350);
FORCEPROP 2 LAST BOM_COST DEBUG
J 0
(2075 3350);
DISPLAY 1.617021 (2075 3350);
PAINT WHITE (2075 3350);
DISPLAY INVISIBLE (2075 3350);
FORCEPROP 2 LAST ROOM CPU_XDP_DEBUG
J 0
(2075 3350);
DISPLAY 1.617021 (2075 3350);
PAINT WHITE (2075 3350);
DISPLAY INVISIBLE (2075 3350);
FORCEPROP 1 LAST OFFPAGE TRUE
J 0
(2200 3175);
PAINT GREEN (2200 3175);
DISPLAY INVISIBLE (2200 3175);
FORCEPROP 1 LAST COMMENT_BODY TRUE
J 0
(1830 3205);
DISPLAY 1.893617 (1830 3205);
PAINT PEACH (1830 3205);
DISPLAY INVISIBLE (1830 3205);
FORCEADD OFFPAGE..2
(3575 2600);
FORCEPROP 2 LAST $XR3 190 
J 0
(4124 2600);
DISPLAY 0.638298 (4124 2600);
PAINT MONO (4124 2600);
FORCEPROP 2 LAST $XR2 175 
J 0
(4004 2600);
DISPLAY 0.638298 (4004 2600);
PAINT MONO (4004 2600);
FORCEPROP 2 LAST $XR1 247 
J 0
(3884 2600);
DISPLAY 0.638298 (3884 2600);
PAINT MONO (3884 2600);
FORCEPROP 2 LAST $XR0 155 
J 0
(3764 2600);
DISPLAY 0.638298 (3764 2600);
PAINT MONO (3764 2600);
FORCEPROP 2 LAST CDS_LIB mstr_standard
J 0
(3575 2600);
PAINT ORANGE (3575 2600);
DISPLAY INVISIBLE (3575 2600);
FORCEPROP 2 LAST BOM_COST MIO_CHASSIS
J 0
(3300 2650);
DISPLAY 1.617021 (3300 2650);
PAINT WHITE (3300 2650);
DISPLAY INVISIBLE (3300 2650);
FORCEPROP 2 LAST ROOM FPB_CONN
J 0
(3300 2650);
DISPLAY 1.617021 (3300 2650);
PAINT WHITE (3300 2650);
DISPLAY INVISIBLE (3300 2650);
FORCEPROP 2 LAST PATH I2
J 0
(4025 2650);
DISPLAY 1.021277 (4025 2650);
PAINT ORANGE (4025 2650);
DISPLAY INVISIBLE (4025 2650);
FORCEPROP 1 LAST OFFPAGE TRUE
J 0
(3900 2475);
DISPLAY 1.404255 (3900 2475);
PAINT GREEN (3900 2475);
DISPLAY INVISIBLE (3900 2475);
FORCEPROP 1 LAST COMMENT_BODY TRUE
J 0
(3530 2505);
DISPLAY 1.404255 (3530 2505);
PAINT PEACH (3530 2505);
DISPLAY INVISIBLE (3530 2505);
FORCEADD OFFPAGE..2
(1875 3350);
FORCEPROP 2 LAST $XR2 112 
J 0
(2304 3350);
DISPLAY 0.638298 (2304 3350);
PAINT MONO (2304 3350);
FORCEPROP 2 LAST $XR1 254 
J 0
(2184 3350);
DISPLAY 0.638298 (2184 3350);
PAINT MONO (2184 3350);
FORCEPROP 2 LAST $XR0 118 
J 0
(2064 3350);
DISPLAY 0.638298 (2064 3350);
PAINT MONO (2064 3350);
FORCEPROP 2 LAST CDS_LIB mstr_standard
J 0
(1875 3350);
DISPLAY 2.212766 (1875 3350);
PAINT ORANGE (1875 3350);
DISPLAY INVISIBLE (1875 3350);
FORCEPROP 2 LAST PATH I20
J 0
(2075 3400);
DISPLAY 1.021277 (2075 3400);
PAINT ORANGE (2075 3400);
DISPLAY INVISIBLE (2075 3400);
FORCEPROP 2 LAST ROOM CPU_XDP_DEBUG
J 0
(2250 3400);
DISPLAY 1.617021 (2250 3400);
PAINT WHITE (2250 3400);
DISPLAY INVISIBLE (2250 3400);
FORCEPROP 2 LAST BOM_COST DEBUG
J 0
(2250 3400);
DISPLAY 1.617021 (2250 3400);
PAINT WHITE (2250 3400);
DISPLAY INVISIBLE (2250 3400);
FORCEPROP 1 LAST OFFPAGE TRUE
J 0
(2200 3225);
PAINT GREEN (2200 3225);
DISPLAY INVISIBLE (2200 3225);
FORCEPROP 1 LAST COMMENT_BODY TRUE
J 0
(1830 3255);
DISPLAY 1.893617 (1830 3255);
PAINT PEACH (1830 3255);
DISPLAY INVISIBLE (1830 3255);
FORCEADD OFFPAGE..2
(1875 3250);
FORCEPROP 2 LAST $XR2 112 
J 0
(2304 3250);
DISPLAY 0.638298 (2304 3250);
PAINT MONO (2304 3250);
FORCEPROP 2 LAST $XR1 254 
J 0
(2184 3250);
DISPLAY 0.638298 (2184 3250);
PAINT MONO (2184 3250);
FORCEPROP 2 LAST $XR0 118 
J 0
(2064 3250);
DISPLAY 0.638298 (2064 3250);
PAINT MONO (2064 3250);
FORCEPROP 2 LAST CDS_LIB mstr_standard
J 0
(1875 3250);
DISPLAY 2.212766 (1875 3250);
PAINT ORANGE (1875 3250);
DISPLAY INVISIBLE (1875 3250);
FORCEPROP 2 LAST BOM_COST DEBUG
J 0
(2250 3300);
DISPLAY 1.617021 (2250 3300);
PAINT WHITE (2250 3300);
DISPLAY INVISIBLE (2250 3300);
FORCEPROP 2 LAST ROOM CPU_XDP_DEBUG
J 0
(2250 3300);
DISPLAY 1.617021 (2250 3300);
PAINT WHITE (2250 3300);
DISPLAY INVISIBLE (2250 3300);
FORCEPROP 2 LAST PATH I21
J 0
(2200 3300);
DISPLAY 1.021277 (2200 3300);
PAINT ORANGE (2200 3300);
DISPLAY INVISIBLE (2200 3300);
FORCEPROP 1 LAST OFFPAGE TRUE
J 0
(2200 3125);
PAINT GREEN (2200 3125);
DISPLAY INVISIBLE (2200 3125);
FORCEPROP 1 LAST COMMENT_BODY TRUE
J 0
(1830 3155);
DISPLAY 1.893617 (1830 3155);
PAINT PEACH (1830 3155);
DISPLAY INVISIBLE (1830 3155);
FORCEADD OFFPAGE..2
(1875 3200);
FORCEPROP 2 LAST $XR1 255 
J 0
(2184 3200);
DISPLAY 0.638298 (2184 3200);
PAINT MONO (2184 3200);
FORCEPROP 2 LAST $XR0 146 
J 0
(2064 3200);
DISPLAY 0.638298 (2064 3200);
PAINT MONO (2064 3200);
FORCEPROP 2 LAST CDS_LIB mstr_standard
J 0
(1875 3200);
DISPLAY 2.212766 (1875 3200);
PAINT ORANGE (1875 3200);
DISPLAY INVISIBLE (1875 3200);
FORCEPROP 2 LAST BOM_COST DEBUG
J 0
(2250 3250);
DISPLAY 1.617021 (2250 3250);
PAINT WHITE (2250 3250);
DISPLAY INVISIBLE (2250 3250);
FORCEPROP 2 LAST ROOM CPU_XDP_DEBUG
J 0
(2250 3250);
DISPLAY 1.617021 (2250 3250);
PAINT WHITE (2250 3250);
DISPLAY INVISIBLE (2250 3250);
FORCEPROP 2 LAST PATH I22
J 0
(2250 3250);
DISPLAY 1.021277 (2250 3250);
PAINT ORANGE (2250 3250);
DISPLAY INVISIBLE (2250 3250);
FORCEPROP 1 LAST OFFPAGE TRUE
J 0
(2200 3075);
PAINT GREEN (2200 3075);
DISPLAY INVISIBLE (2200 3075);
FORCEPROP 1 LAST COMMENT_BODY TRUE
J 0
(1830 3105);
DISPLAY 1.893617 (1830 3105);
PAINT PEACH (1830 3105);
DISPLAY INVISIBLE (1830 3105);
FORCEADD OFFPAGE..5
(1750 2150);
FORCEPROP 2 LAST $XR2 190 
J 0
(1255 2150);
DISPLAY 0.638298 (1255 2150);
PAINT MONO (1255 2150);
FORCEPROP 2 LAST $XR1 144 
J 0
(1375 2150);
DISPLAY 0.638298 (1375 2150);
PAINT MONO (1375 2150);
FORCEPROP 2 LAST $XR0 111 
J 0
(1495 2150);
DISPLAY 0.638298 (1495 2150);
PAINT MONO (1495 2150);
FORCEPROP 2 LAST CDS_LIB mstr_standard
J 0
(1750 2150);
DISPLAY 2.212766 (1750 2150);
PAINT ORANGE (1750 2150);
DISPLAY INVISIBLE (1750 2150);
FORCEPROP 2 LAST ROOM CPU_XDP_DEBUG
J 0
(1500 2200);
DISPLAY 1.617021 (1500 2200);
PAINT WHITE (1500 2200);
DISPLAY INVISIBLE (1500 2200);
FORCEPROP 2 LAST BOM_COST DEBUG
J 0
(1500 2200);
DISPLAY 1.617021 (1500 2200);
PAINT WHITE (1500 2200);
DISPLAY INVISIBLE (1500 2200);
FORCEPROP 2 LAST PATH I23
J 0
(1500 2200);
DISPLAY 1.021277 (1500 2200);
PAINT ORANGE (1500 2200);
DISPLAY INVISIBLE (1500 2200);
FORCEPROP 1 LAST OFFPAGE TRUE
J 0
(2075 2025);
PAINT GREEN (2075 2025);
DISPLAY INVISIBLE (2075 2025);
FORCEPROP 1 LAST COMMENT_BODY TRUE
J 0
(1850 2075);
DISPLAY 1.893617 (1850 2075);
PAINT PEACH (1850 2075);
DISPLAY INVISIBLE (1850 2075);
FORCEADD GND..1
(875 2625);
FORCEPROP 3 LASTPIN (875 2675) SIG_NAME GND\g
J 0
(885 2685);
DISPLAY 0.659574 (885 2685);
PAINT MONO (885 2685);
DISPLAY INVISIBLE (885 2685);
FORCEPROP 2 LAST ROOM CPU_XDP_DEBUG
J 0
(425 2700);
DISPLAY 1.617021 (425 2700);
PAINT WHITE (425 2700);
DISPLAY INVISIBLE (425 2700);
FORCEPROP 2 LAST BOM_COST DEBUG
J 0
(725 2700);
DISPLAY 1.617021 (725 2700);
PAINT WHITE (725 2700);
DISPLAY INVISIBLE (725 2700);
FORCEPROP 1 LAST VOLTAGE 0.0V
J 0
(830 2582);
DISPLAY 0.340426 (830 2582);
PAINT SKYBLUE (830 2582);
DISPLAY INVISIBLE (830 2582);
FORCEPROP 2 LAST CDS_LIB mstr_symbols
J 0
(875 2625);
DISPLAY 2.212766 (875 2625);
PAINT ORANGE (875 2625);
DISPLAY INVISIBLE (875 2625);
FORCEPROP 1 LAST SIZE 1B
J 0
(950 2575);
DISPLAY 1.893617 (950 2575);
PAINT GREEN (950 2575);
DISPLAY INVISIBLE (950 2575);
FORCEPROP 1 LAST PATH I24
J 0
(950 2625);
DISPLAY 0.872340 (950 2625);
PAINT AQUA (950 2625);
DISPLAY INVISIBLE (950 2625);
FORCEPROP 1 LAST BODY_TYPE PLUMBING
J 0
(830 2582);
DISPLAY 0.340426 (830 2582);
PAINT GREEN (830 2582);
DISPLAY INVISIBLE (830 2582);
FORCEPROP 1 LAST HDL_POWER GND
J 0
(875 2775);
PAINT GREEN (875 2775);
DISPLAY INVISIBLE (875 2775);
FORCEADD CAP_A..1
R 2
(750 2925);
FORCEPROP 1 LAST PART_NUMBER D97712-004
J 2
(700 2775);
DISPLAY 0.617021 (700 2775);
PAINT BLUE (700 2775);
FORCEPROP 1 LAST PACK_TYPE 0402V
J 2
(700 2725);
DISPLAY 0.617021 (700 2725);
PAINT SKYBLUE (700 2725);
FORCEPROP 1 LASTPIN (750 2825) $PN 2
J 2
(740 2805);
DISPLAY 0.617021 (740 2805);
PAINT WHITE (740 2805);
FORCEPROP 1 LASTPIN (750 3025) $PN 1
J 2
(740 3005);
DISPLAY 0.617021 (740 3005);
PAINT WHITE (740 3005);
FORCEPROP 1 LAST MATERIAL X6S
J 2
(700 2825);
DISPLAY 0.617021 (700 2825);
PAINT SKYBLUE (700 2825);
FORCEPROP 1 LAST VOLTAGE 6.3V
J 2
(700 2925);
DISPLAY 0.617021 (700 2925);
PAINT SKYBLUE (700 2925);
FORCEPROP 1 LAST TOLERANCE 10%
J 2
(700 2875);
DISPLAY 0.617021 (700 2875);
PAINT SKYBLUE (700 2875);
FORCEPROP 1 LAST VALUE 1.0UF
J 2
(700 2975);
DISPLAY 0.617021 (700 2975);
PAINT SKYBLUE (700 2975);
FORCEPROP 1 LAST LOCATION C9A6
J 2
(700 3025);
DISPLAY 0.617021 (700 3025);
PAINT AQUA (700 3025);
FORCEPROP 2 LAST CDS_LIB dev_discrete
J 0
(750 2925);
PAINT ORANGE (750 2925);
DISPLAY INVISIBLE (750 2925);
FORCEPROP 2 LAST BOM_COST DEBUG
J 0
(700 3000);
DISPLAY 1.617021 (700 3000);
PAINT WHITE (700 3000);
DISPLAY INVISIBLE (700 3000);
FORCEPROP 2 LAST CDS_LOCATION C9A6
J 2
(700 3000);
DISPLAY 0.617021 (700 3000);
PAINT AQUA (700 3000);
DISPLAY INVISIBLE (700 3000);
FORCEPROP 2 LAST ROOM DEBUG
J 2
(700 3025);
DISPLAY 1.617021 (700 3025);
PAINT WHITE (700 3025);
DISPLAY INVISIBLE (700 3025);
FORCEPROP 1 LAST PATH I25
J 2
(700 3075);
DISPLAY 0.978723 (700 3075);
PAINT WHITE (700 3075);
DISPLAY INVISIBLE (700 3075);
FORCEPROP 2 LAST $SEC 1
J 0
(700 3125);
PAINT MONO (700 3125);
DISPLAY INVISIBLE (700 3125);
FORCEPROP 2 LAST CDS_SEC 1
J 0
(700 3125);
PAINT MONO (700 3125);
DISPLAY INVISIBLE (700 3125);
FORCEADD SCONN60_C21100002..1
(350 3950);
FORCEPROP 2 LASTPIN (200 3200) $PN 59
J 2
(190 3210);
DISPLAY 0.617021 (190 3210);
PAINT ORANGE (190 3210);
FORCEPROP 2 LASTPIN (200 3250) $PN 57
J 2
(190 3260);
DISPLAY 0.617021 (190 3260);
PAINT ORANGE (190 3260);
FORCEPROP 2 LASTPIN (200 3300) $PN 55
J 2
(190 3310);
DISPLAY 0.617021 (190 3310);
PAINT ORANGE (190 3310);
FORCEPROP 2 LASTPIN (200 3350) $PN 53
J 2
(190 3360);
DISPLAY 0.617021 (190 3360);
PAINT ORANGE (190 3360);
FORCEPROP 2 LASTPIN (200 3400) $PN 51
J 2
(190 3410);
DISPLAY 0.617021 (190 3410);
PAINT ORANGE (190 3410);
FORCEPROP 2 LASTPIN (200 3450) $PN 49
J 2
(190 3460);
DISPLAY 0.617021 (190 3460);
PAINT ORANGE (190 3460);
FORCEPROP 2 LASTPIN (200 3500) $PN 47
J 2
(190 3510);
DISPLAY 0.617021 (190 3510);
PAINT ORANGE (190 3510);
FORCEPROP 2 LASTPIN (200 3550) $PN 45
J 2
(190 3560);
DISPLAY 0.617021 (190 3560);
PAINT ORANGE (190 3560);
FORCEPROP 2 LASTPIN (200 3600) $PN 43
J 2
(190 3610);
DISPLAY 0.617021 (190 3610);
PAINT ORANGE (190 3610);
FORCEPROP 2 LASTPIN (200 3650) $PN 41
J 2
(190 3660);
DISPLAY 0.617021 (190 3660);
PAINT ORANGE (190 3660);
FORCEPROP 2 LASTPIN (200 3700) $PN 39
J 2
(190 3710);
DISPLAY 0.617021 (190 3710);
PAINT ORANGE (190 3710);
FORCEPROP 2 LASTPIN (200 3750) $PN 37
J 2
(190 3760);
DISPLAY 0.617021 (190 3760);
PAINT ORANGE (190 3760);
FORCEPROP 2 LASTPIN (200 3800) $PN 35
J 2
(190 3810);
DISPLAY 0.617021 (190 3810);
PAINT ORANGE (190 3810);
FORCEPROP 2 LASTPIN (200 3850) $PN 33
J 2
(190 3860);
DISPLAY 0.617021 (190 3860);
PAINT ORANGE (190 3860);
FORCEPROP 2 LASTPIN (200 3900) $PN 31
J 2
(190 3910);
DISPLAY 0.617021 (190 3910);
PAINT ORANGE (190 3910);
FORCEPROP 2 LASTPIN (200 3950) $PN 29
J 2
(190 3960);
DISPLAY 0.617021 (190 3960);
PAINT ORANGE (190 3960);
FORCEPROP 2 LASTPIN (200 4000) $PN 27
J 2
(190 4010);
DISPLAY 0.617021 (190 4010);
PAINT ORANGE (190 4010);
FORCEPROP 2 LASTPIN (200 4050) $PN 25
J 2
(190 4060);
DISPLAY 0.617021 (190 4060);
PAINT ORANGE (190 4060);
FORCEPROP 2 LASTPIN (500 3350) $PN 54
J 0
(510 3360);
DISPLAY 0.617021 (510 3360);
PAINT ORANGE (510 3360);
FORCEPROP 2 LASTPIN (500 3400) $PN 52
J 0
(510 3410);
DISPLAY 0.617021 (510 3410);
PAINT ORANGE (510 3410);
FORCEPROP 2 LASTPIN (500 3200) $PN 60
J 0
(510 3210);
DISPLAY 0.617021 (510 3210);
PAINT ORANGE (510 3210);
FORCEPROP 2 LASTPIN (500 3250) $PN 58
J 0
(510 3260);
DISPLAY 0.617021 (510 3260);
PAINT ORANGE (510 3260);
FORCEPROP 2 LASTPIN (500 3300) $PN 56
J 0
(510 3310);
DISPLAY 0.617021 (510 3310);
PAINT ORANGE (510 3310);
FORCEPROP 2 LASTPIN (500 3450) $PN 50
J 0
(510 3460);
DISPLAY 0.617021 (510 3460);
PAINT ORANGE (510 3460);
FORCEPROP 2 LASTPIN (500 3500) $PN 48
J 0
(510 3510);
DISPLAY 0.617021 (510 3510);
PAINT ORANGE (510 3510);
FORCEPROP 2 LASTPIN (500 3700) $PN 40
J 0
(510 3710);
DISPLAY 0.617021 (510 3710);
PAINT ORANGE (510 3710);
FORCEPROP 2 LASTPIN (500 3750) $PN 38
J 0
(510 3760);
DISPLAY 0.617021 (510 3760);
PAINT ORANGE (510 3760);
FORCEPROP 2 LASTPIN (500 3800) $PN 36
J 0
(510 3810);
DISPLAY 0.617021 (510 3810);
PAINT ORANGE (510 3810);
FORCEPROP 2 LASTPIN (500 3850) $PN 34
J 0
(510 3860);
DISPLAY 0.617021 (510 3860);
PAINT ORANGE (510 3860);
FORCEPROP 2 LASTPIN (500 3900) $PN 32
J 0
(510 3910);
DISPLAY 0.617021 (510 3910);
PAINT ORANGE (510 3910);
FORCEPROP 2 LASTPIN (500 3950) $PN 30
J 0
(510 3960);
DISPLAY 0.617021 (510 3960);
PAINT ORANGE (510 3960);
FORCEPROP 2 LASTPIN (500 4000) $PN 28
J 0
(510 4010);
DISPLAY 0.617021 (510 4010);
PAINT ORANGE (510 4010);
FORCEPROP 2 LASTPIN (500 4050) $PN 26
J 0
(510 4060);
DISPLAY 0.617021 (510 4060);
PAINT ORANGE (510 4060);
FORCEPROP 2 LASTPIN (500 3600) $PN 44
J 0
(510 3610);
DISPLAY 0.617021 (510 3610);
PAINT ORANGE (510 3610);
FORCEPROP 2 LASTPIN (500 3550) $PN 46
J 0
(510 3560);
DISPLAY 0.617021 (510 3560);
PAINT ORANGE (510 3560);
FORCEPROP 2 LASTPIN (500 3650) $PN 42
J 0
(510 3660);
DISPLAY 0.617021 (510 3660);
PAINT ORANGE (510 3660);
FORCEPROP 2 LASTPIN (200 4100) $PN 23
J 2
(190 4110);
DISPLAY 0.617021 (190 4110);
PAINT ORANGE (190 4110);
FORCEPROP 2 LASTPIN (200 4150) $PN 21
J 2
(190 4160);
DISPLAY 0.617021 (190 4160);
PAINT ORANGE (190 4160);
FORCEPROP 2 LASTPIN (200 4200) $PN 19
J 2
(190 4210);
DISPLAY 0.617021 (190 4210);
PAINT ORANGE (190 4210);
FORCEPROP 2 LASTPIN (200 4250) $PN 17
J 2
(190 4260);
DISPLAY 0.617021 (190 4260);
PAINT ORANGE (190 4260);
FORCEPROP 2 LASTPIN (200 4300) $PN 15
J 2
(190 4310);
DISPLAY 0.617021 (190 4310);
PAINT ORANGE (190 4310);
FORCEPROP 2 LASTPIN (200 4350) $PN 13
J 2
(190 4360);
DISPLAY 0.617021 (190 4360);
PAINT ORANGE (190 4360);
FORCEPROP 2 LASTPIN (200 4400) $PN 11
J 2
(190 4410);
DISPLAY 0.617021 (190 4410);
PAINT ORANGE (190 4410);
FORCEPROP 2 LASTPIN (200 4450) $PN 9
J 2
(190 4460);
DISPLAY 0.617021 (190 4460);
PAINT ORANGE (190 4460);
FORCEPROP 2 LASTPIN (200 4500) $PN 7
J 2
(190 4510);
DISPLAY 0.617021 (190 4510);
PAINT ORANGE (190 4510);
FORCEPROP 2 LASTPIN (200 4550) $PN 5
J 2
(190 4560);
DISPLAY 0.617021 (190 4560);
PAINT ORANGE (190 4560);
FORCEPROP 2 LASTPIN (200 4600) $PN 3
J 2
(190 4610);
DISPLAY 0.617021 (190 4610);
PAINT ORANGE (190 4610);
FORCEPROP 2 LASTPIN (200 4650) $PN 1
J 2
(190 4660);
DISPLAY 0.617021 (190 4660);
PAINT ORANGE (190 4660);
FORCEPROP 1 LAST PART_NUMBER C21100-002
J 1
(350 4700);
DISPLAY 0.617021 (350 4700);
PAINT BLUE (350 4700);
FORCEPROP 1 LAST LOCATION J9A3
J 1
(350 4750);
DISPLAY 0.617021 (350 4750);
PAINT AQUA (350 4750);
FORCEPROP 1 LAST PACK_TYPE SMLF
J 1
(350 4850);
DISPLAY 0.617021 (350 4850);
PAINT SKYBLUE (350 4850);
FORCEPROP 1 LAST MATERIAL CONN
J 1
(350 4800);
DISPLAY 0.617021 (350 4800);
PAINT SKYBLUE (350 4800);
FORCEPROP 2 LASTPIN (500 4100) $PN 24
J 0
(510 4110);
DISPLAY 0.617021 (510 4110);
PAINT ORANGE (510 4110);
FORCEPROP 2 LASTPIN (500 4150) $PN 22
J 0
(510 4160);
DISPLAY 0.617021 (510 4160);
PAINT ORANGE (510 4160);
FORCEPROP 2 LASTPIN (500 4200) $PN 20
J 0
(510 4210);
DISPLAY 0.617021 (510 4210);
PAINT ORANGE (510 4210);
FORCEPROP 2 LASTPIN (500 4250) $PN 18
J 0
(510 4260);
DISPLAY 0.617021 (510 4260);
PAINT ORANGE (510 4260);
FORCEPROP 2 LASTPIN (500 4300) $PN 16
J 0
(510 4310);
DISPLAY 0.617021 (510 4310);
PAINT ORANGE (510 4310);
FORCEPROP 2 LASTPIN (500 4350) $PN 14
J 0
(510 4360);
DISPLAY 0.617021 (510 4360);
PAINT ORANGE (510 4360);
FORCEPROP 2 LASTPIN (500 4400) $PN 12
J 0
(510 4410);
DISPLAY 0.617021 (510 4410);
PAINT ORANGE (510 4410);
FORCEPROP 2 LASTPIN (500 4450) $PN 10
J 0
(510 4460);
DISPLAY 0.617021 (510 4460);
PAINT ORANGE (510 4460);
FORCEPROP 2 LASTPIN (500 4500) $PN 8
J 0
(510 4510);
DISPLAY 0.617021 (510 4510);
PAINT ORANGE (510 4510);
FORCEPROP 2 LASTPIN (500 4550) $PN 6
J 0
(510 4560);
DISPLAY 0.617021 (510 4560);
PAINT ORANGE (510 4560);
FORCEPROP 2 LASTPIN (500 4600) $PN 4
J 0
(510 4610);
DISPLAY 0.617021 (510 4610);
PAINT ORANGE (510 4610);
FORCEPROP 2 LASTPIN (500 4650) $PN 2
J 0
(510 4660);
DISPLAY 0.617021 (510 4660);
PAINT ORANGE (510 4660);
FORCEPROP 2 LAST CDS_LIB mstr_sconn
J 0
(350 3950);
PAINT ORANGE (350 3950);
DISPLAY INVISIBLE (350 3950);
FORCEPROP 1 LAST ALLOW_CONNECT TRUE
J 1
(375 4575);
DISPLAY 0.872340 (375 4575);
PAINT GREEN (375 4575);
DISPLAY INVISIBLE (375 4575);
FORCEPROP 2 LAST CDS_LOCATION J9A3
J 1
(350 4750);
DISPLAY 0.617021 (350 4750);
PAINT AQUA (350 4750);
DISPLAY INVISIBLE (350 4750);
FORCEPROP 2 LAST ROOM DEBUG
J 0
(350 4900);
DISPLAY 1.617021 (350 4900);
PAINT WHITE (350 4900);
DISPLAY INVISIBLE (350 4900);
FORCEPROP 2 LAST BOM_COST DEBUG
J 0
(350 4900);
DISPLAY 1.617021 (350 4900);
PAINT WHITE (350 4900);
DISPLAY INVISIBLE (350 4900);
FORCEPROP 1 LAST PATH I26
J 1
(350 5100);
DISPLAY 0.872340 (350 5100);
PAINT WHITE (350 5100);
DISPLAY INVISIBLE (350 5100);
FORCEPROP 2 LAST SEC_TYPE SMLF
J 0
(350 5150);
DISPLAY 1.021277 (350 5150);
PAINT ORANGE (350 5150);
DISPLAY INVISIBLE (350 5150);
FORCEPROP 2 LAST SEC 1
J 0
(350 5150);
DISPLAY 0.680851 (350 5150);
PAINT MONO (350 5150);
DISPLAY INVISIBLE (350 5150);
FORCEADD OFFPAGE..5
(1750 1700);
FORCEPROP 2 LAST $XR0 111 
J 0
(1495 1700);
DISPLAY 0.638298 (1495 1700);
PAINT MONO (1495 1700);
FORCEPROP 2 LAST CDS_LIB mstr_standard
J 0
(1750 1700);
DISPLAY 2.212766 (1750 1700);
PAINT ORANGE (1750 1700);
DISPLAY INVISIBLE (1750 1700);
FORCEPROP 2 LAST ROOM CPU_XDP_DEBUG
J 0
(1500 1750);
DISPLAY 1.617021 (1500 1750);
PAINT WHITE (1500 1750);
DISPLAY INVISIBLE (1500 1750);
FORCEPROP 2 LAST BOM_COST DEBUG
J 0
(1500 1750);
DISPLAY 1.617021 (1500 1750);
PAINT WHITE (1500 1750);
DISPLAY INVISIBLE (1500 1750);
FORCEPROP 2 LAST PATH I27
J 0
(1500 1750);
DISPLAY 1.021277 (1500 1750);
PAINT ORANGE (1500 1750);
DISPLAY INVISIBLE (1500 1750);
FORCEPROP 1 LAST OFFPAGE TRUE
J 0
(2075 1575);
PAINT GREEN (2075 1575);
DISPLAY INVISIBLE (2075 1575);
FORCEPROP 1 LAST COMMENT_BODY TRUE
J 0
(1850 1625);
DISPLAY 1.893617 (1850 1625);
PAINT PEACH (1850 1625);
DISPLAY INVISIBLE (1850 1625);
FORCEADD OFFPAGE..5
(1750 1150);
FORCEPROP 2 LAST $XR1 190 
J 0
(1375 1150);
DISPLAY 0.638298 (1375 1150);
PAINT MONO (1375 1150);
FORCEPROP 2 LAST $XR0 111 
J 0
(1495 1150);
DISPLAY 0.638298 (1495 1150);
PAINT MONO (1495 1150);
FORCEPROP 2 LAST PATH I28
J 0
(1500 1200);
DISPLAY 1.021277 (1500 1200);
PAINT ORANGE (1500 1200);
DISPLAY INVISIBLE (1500 1200);
FORCEPROP 2 LAST BOM_COST DEBUG
J 0
(1500 1200);
DISPLAY 1.617021 (1500 1200);
PAINT WHITE (1500 1200);
DISPLAY INVISIBLE (1500 1200);
FORCEPROP 2 LAST ROOM CPU_XDP_DEBUG
J 0
(1500 1200);
DISPLAY 1.617021 (1500 1200);
PAINT WHITE (1500 1200);
DISPLAY INVISIBLE (1500 1200);
FORCEPROP 2 LAST CDS_LIB mstr_standard
J 0
(1750 1150);
DISPLAY 2.212766 (1750 1150);
PAINT ORANGE (1750 1150);
DISPLAY INVISIBLE (1750 1150);
FORCEPROP 1 LAST OFFPAGE TRUE
J 0
(2075 1025);
PAINT GREEN (2075 1025);
DISPLAY INVISIBLE (2075 1025);
FORCEPROP 1 LAST COMMENT_BODY TRUE
J 0
(1850 1075);
DISPLAY 1.893617 (1850 1075);
PAINT PEACH (1850 1075);
DISPLAY INVISIBLE (1850 1075);
FORCEADD CAP_A..1
(0 2925);
FORCEPROP 1 LAST PACK_TYPE 0402V
J 0
(50 2725);
DISPLAY 0.617021 (50 2725);
PAINT SKYBLUE (50 2725);
FORCEPROP 1 LAST MATERIAL X6S
J 0
(50 2825);
DISPLAY 0.617021 (50 2825);
PAINT SKYBLUE (50 2825);
FORCEPROP 1 LASTPIN (0 3025) $PN 1
J 0
(10 3005);
DISPLAY 0.617021 (10 3005);
PAINT WHITE (10 3005);
FORCEPROP 1 LASTPIN (0 2825) $PN 2
J 0
(10 2805);
DISPLAY 0.617021 (10 2805);
PAINT WHITE (10 2805);
FORCEPROP 1 LAST PART_NUMBER D97712-004
J 0
(50 2775);
DISPLAY 0.617021 (50 2775);
PAINT BLUE (50 2775);
FORCEPROP 1 LAST TOLERANCE 10%
J 0
(50 2875);
DISPLAY 0.617021 (50 2875);
PAINT SKYBLUE (50 2875);
FORCEPROP 1 LAST VOLTAGE 6.3V
J 0
(50 2925);
DISPLAY 0.617021 (50 2925);
PAINT SKYBLUE (50 2925);
FORCEPROP 1 LAST LOCATION C1L5
J 0
(50 3025);
DISPLAY 0.617021 (50 3025);
PAINT AQUA (50 3025);
FORCEPROP 1 LAST VALUE 1.0UF
J 0
(50 2975);
DISPLAY 0.617021 (50 2975);
PAINT SKYBLUE (50 2975);
FORCEPROP 2 LAST CDS_LIB dev_discrete
J 0
(0 2925);
PAINT ORANGE (0 2925);
DISPLAY INVISIBLE (0 2925);
FORCEPROP 2 LAST CDS_LOCATION C1L5
J 0
(50 3000);
DISPLAY 0.617021 (50 3000);
PAINT AQUA (50 3000);
DISPLAY INVISIBLE (50 3000);
FORCEPROP 2 LAST BOM_COST DEBUG
J 0
(50 3000);
DISPLAY 1.617021 (50 3000);
PAINT WHITE (50 3000);
DISPLAY INVISIBLE (50 3000);
FORCEPROP 2 LAST ROOM DEBUG
J 0
(50 3025);
DISPLAY 1.617021 (50 3025);
PAINT WHITE (50 3025);
DISPLAY INVISIBLE (50 3025);
FORCEPROP 2 LAST CDS_SEC 1
J 0
(50 3125);
PAINT MONO (50 3125);
DISPLAY INVISIBLE (50 3125);
FORCEPROP 2 LAST $SEC 1
J 0
(50 3125);
PAINT MONO (50 3125);
DISPLAY INVISIBLE (50 3125);
FORCEPROP 1 LAST PATH I30
J 0
(50 3075);
DISPLAY 0.978723 (50 3075);
PAINT WHITE (50 3075);
DISPLAY INVISIBLE (50 3075);
FORCEADD OFFPAGE..5
(-1175 4600);
FORCEPROP 2 LAST $XR2 112 
J 0
(-1670 4600);
DISPLAY 0.638298 (-1670 4600);
PAINT MONO (-1670 4600);
FORCEPROP 2 LAST $XR1 254 
J 0
(-1550 4600);
DISPLAY 0.638298 (-1550 4600);
PAINT MONO (-1550 4600);
FORCEPROP 2 LAST $XR0 118 
J 0
(-1430 4600);
DISPLAY 0.638298 (-1430 4600);
PAINT MONO (-1430 4600);
FORCEPROP 2 LAST CDS_LIB mstr_standard
J 0
(-1175 4600);
DISPLAY 2.212766 (-1175 4600);
PAINT ORANGE (-1175 4600);
DISPLAY INVISIBLE (-1175 4600);
FORCEPROP 2 LAST PATH I31
J 0
(-1425 4650);
DISPLAY 1.021277 (-1425 4650);
PAINT ORANGE (-1425 4650);
DISPLAY INVISIBLE (-1425 4650);
FORCEPROP 2 LAST BOM_COST DEBUG
J 0
(-1375 4650);
DISPLAY 1.617021 (-1375 4650);
PAINT WHITE (-1375 4650);
DISPLAY INVISIBLE (-1375 4650);
FORCEPROP 2 LAST ROOM CPU_XDP_DEBUG
J 0
(-1375 4650);
DISPLAY 1.617021 (-1375 4650);
PAINT WHITE (-1375 4650);
DISPLAY INVISIBLE (-1375 4650);
FORCEPROP 1 LAST OFFPAGE TRUE
J 0
(-850 4475);
PAINT GREEN (-850 4475);
DISPLAY INVISIBLE (-850 4475);
FORCEPROP 1 LAST COMMENT_BODY TRUE
J 0
(-1075 4525);
DISPLAY 1.893617 (-1075 4525);
PAINT PEACH (-1075 4525);
DISPLAY INVISIBLE (-1075 4525);
FORCEADD OFFPAGE..1
(-1175 4550);
FORCEPROP 2 LAST $XR2 255 
J 0
(-1697 4550);
DISPLAY 0.638298 (-1697 4550);
PAINT MONO (-1697 4550);
FORCEPROP 2 LAST $XR1 118 
J 0
(-1577 4550);
DISPLAY 0.638298 (-1577 4550);
PAINT MONO (-1577 4550);
FORCEPROP 2 LAST $XR0 112 
J 0
(-1457 4550);
DISPLAY 0.638298 (-1457 4550);
PAINT MONO (-1457 4550);
FORCEPROP 2 LAST PATH I32
J 0
(-1450 4600);
DISPLAY 1.021277 (-1450 4600);
PAINT ORANGE (-1450 4600);
DISPLAY INVISIBLE (-1450 4600);
FORCEPROP 2 LAST CDS_LIB mstr_standard
J 0
(-1175 4550);
DISPLAY 2.212766 (-1175 4550);
PAINT ORANGE (-1175 4550);
DISPLAY INVISIBLE (-1175 4550);
FORCEPROP 2 LAST ROOM CPU_XDP_DEBUG
J 0
(-1375 4600);
DISPLAY 1.617021 (-1375 4600);
PAINT WHITE (-1375 4600);
DISPLAY INVISIBLE (-1375 4600);
FORCEPROP 2 LAST BOM_COST DEBUG
J 0
(-1375 4600);
DISPLAY 1.617021 (-1375 4600);
PAINT WHITE (-1375 4600);
DISPLAY INVISIBLE (-1375 4600);
FORCEPROP 1 LAST OFFPAGE TRUE
J 0
(-850 4425);
PAINT GREEN (-850 4425);
DISPLAY INVISIBLE (-850 4425);
FORCEPROP 1 LAST COMMENT_BODY TRUE
J 0
(-1050 4450);
DISPLAY 1.893617 (-1050 4450);
PAINT PEACH (-1050 4450);
DISPLAY INVISIBLE (-1050 4450);
FORCEADD RES..1
(-2100 4650);
FORCEPROP 1 LAST WATTAGE 1/16W
J 2
(-2075 4550);
DISPLAY 0.617021 (-2075 4550);
PAINT SKYBLUE (-2075 4550);
FORCEPROP 1 LAST LOCATION R2P2
J 0
(-2150 4700);
DISPLAY 0.617021 (-2150 4700);
PAINT AQUA (-2150 4700);
FORCEPROP 1 LAST TOLERANCE 1%
J 0
(-2300 4550);
DISPLAY 0.617021 (-2300 4550);
PAINT SKYBLUE (-2300 4550);
FORCEPROP 1 LAST VALUE 1.00K
J 2
(-2350 4550);
DISPLAY 0.617021 (-2350 4550);
PAINT SKYBLUE (-2350 4550);
FORCEPROP 1 LAST PART_NUMBER G21796-026
J 0
(-2400 4600);
DISPLAY 0.617021 (-2400 4600);
PAINT BLUE (-2400 4600);
FORCEPROP 1 LAST PACK_TYPE 0402
J 0
(-2050 4600);
DISPLAY 0.617021 (-2050 4600);
PAINT SKYBLUE (-2050 4600);
FORCEPROP 1 LAST MATERIAL CHIP
J 0
(-2000 4550);
DISPLAY 0.617021 (-2000 4550);
PAINT SKYBLUE (-2000 4550);
FORCEPROP 1 LASTPIN (-2200 4650) $PN 1
J 0
(-2188 4662);
DISPLAY 0.617021 (-2188 4662);
PAINT WHITE (-2188 4662);
FORCEPROP 1 LASTPIN (-2000 4650) $PN 2
J 0
(-2038 4662);
DISPLAY 0.617021 (-2038 4662);
PAINT WHITE (-2038 4662);
FORCEPROP 1 LAST PATH I37
J 0
(-2150 4800);
DISPLAY 0.978723 (-2150 4800);
PAINT WHITE (-2150 4800);
DISPLAY INVISIBLE (-2150 4800);
FORCEPROP 2 LAST CDS_LOCATION R2P2
J 0
(-2150 4700);
DISPLAY 0.617021 (-2150 4700);
PAINT AQUA (-2150 4700);
DISPLAY INVISIBLE (-2150 4700);
FORCEPROP 2 LAST BOM_COST DEBUG
J 0
(-2150 4750);
DISPLAY 1.617021 (-2150 4750);
PAINT WHITE (-2150 4750);
DISPLAY INVISIBLE (-2150 4750);
FORCEPROP 2 LAST SEC_TYPE 0402
J 0
(-2150 4750);
DISPLAY 1.659574 (-2150 4750);
PAINT ORANGE (-2150 4750);
DISPLAY INVISIBLE (-2150 4750);
FORCEPROP 2 LAST CDS_LIB mstr_discrete
J 0
(-2100 4650);
DISPLAY 2.212766 (-2100 4650);
PAINT ORANGE (-2100 4650);
DISPLAY INVISIBLE (-2100 4650);
FORCEPROP 2 LAST SEC 1
J 0
(-2150 4850);
DISPLAY 1.510638 (-2150 4850);
PAINT MONO (-2150 4850);
DISPLAY INVISIBLE (-2150 4850);
FORCEPROP 2 LAST ROOM DEBUG
J 0
(-2150 4800);
DISPLAY 1.617021 (-2150 4800);
PAINT WHITE (-2150 4800);
DISPLAY INVISIBLE (-2150 4800);
FORCEADD OFFPAGE..5
(-2950 4650);
FORCEPROP 2 LAST $XR2 154 
J 0
(-3475 4650);
DISPLAY 0.638298 (-3475 4650);
PAINT MONO (-3475 4650);
FORCEPROP 2 LAST $XR1 125 
J 0
(-3355 4650);
DISPLAY 0.638298 (-3355 4650);
PAINT MONO (-3355 4650);
FORCEPROP 2 LAST $XR0 121 
J 0
(-3235 4650);
DISPLAY 0.638298 (-3235 4650);
PAINT MONO (-3235 4650);
FORCEPROP 2 LAST BOM_COST DEBUG
J 0
(-3150 4700);
DISPLAY 1.617021 (-3150 4700);
PAINT WHITE (-3150 4700);
DISPLAY INVISIBLE (-3150 4700);
FORCEPROP 2 LAST ROOM CPU_XDP_DEBUG
J 0
(-3150 4700);
DISPLAY 1.617021 (-3150 4700);
PAINT WHITE (-3150 4700);
DISPLAY INVISIBLE (-3150 4700);
FORCEPROP 2 LAST PATH I38
J 0
(-3200 4700);
DISPLAY 1.021277 (-3200 4700);
PAINT ORANGE (-3200 4700);
DISPLAY INVISIBLE (-3200 4700);
FORCEPROP 2 LAST CDS_LIB mstr_standard
J 0
(-2950 4650);
DISPLAY 2.212766 (-2950 4650);
PAINT ORANGE (-2950 4650);
DISPLAY INVISIBLE (-2950 4650);
FORCEPROP 1 LAST OFFPAGE TRUE
J 0
(-2625 4525);
PAINT GREEN (-2625 4525);
DISPLAY INVISIBLE (-2625 4525);
FORCEPROP 1 LAST COMMENT_BODY TRUE
J 0
(-2850 4575);
DISPLAY 1.893617 (-2850 4575);
PAINT PEACH (-2850 4575);
DISPLAY INVISIBLE (-2850 4575);
FORCEADD GND..1
(-100 2625);
FORCEPROP 3 LASTPIN (-100 2675) SIG_NAME GND\g
J 0
(-90 2685);
DISPLAY 0.659574 (-90 2685);
PAINT MONO (-90 2685);
DISPLAY INVISIBLE (-90 2685);
FORCEPROP 2 LAST ROOM CPU_XDP_DEBUG
J 0
(-550 2700);
DISPLAY 1.617021 (-550 2700);
PAINT WHITE (-550 2700);
DISPLAY INVISIBLE (-550 2700);
FORCEPROP 2 LAST BOM_COST DEBUG
J 0
(-250 2700);
DISPLAY 1.617021 (-250 2700);
PAINT WHITE (-250 2700);
DISPLAY INVISIBLE (-250 2700);
FORCEPROP 1 LAST VOLTAGE 0.0V
J 0
(-145 2582);
DISPLAY 0.340426 (-145 2582);
PAINT SKYBLUE (-145 2582);
DISPLAY INVISIBLE (-145 2582);
FORCEPROP 1 LAST SIZE 1B
J 0
(-25 2575);
DISPLAY 1.893617 (-25 2575);
PAINT GREEN (-25 2575);
DISPLAY INVISIBLE (-25 2575);
FORCEPROP 1 LAST PATH I39
J 0
(-25 2625);
DISPLAY 0.872340 (-25 2625);
PAINT AQUA (-25 2625);
DISPLAY INVISIBLE (-25 2625);
FORCEPROP 2 LAST CDS_LIB mstr_symbols
J 0
(-100 2625);
DISPLAY 2.212766 (-100 2625);
PAINT ORANGE (-100 2625);
DISPLAY INVISIBLE (-100 2625);
FORCEPROP 1 LAST BODY_TYPE PLUMBING
J 0
(-145 2582);
DISPLAY 0.340426 (-145 2582);
PAINT GREEN (-145 2582);
DISPLAY INVISIBLE (-145 2582);
FORCEPROP 1 LAST HDL_POWER GND
J 0
(-100 2775);
PAINT GREEN (-100 2775);
DISPLAY INVISIBLE (-100 2775);
FORCEADD OFFPAGE..2
(2850 3500);
FORCEPROP 2 LAST $XR0 111 
J 0
(3039 3500);
DISPLAY 0.638298 (3039 3500);
PAINT MONO (3039 3500);
FORCEPROP 2 LAST CDS_LIB mstr_standard
J 0
(2850 3500);
PAINT ORANGE (2850 3500);
DISPLAY INVISIBLE (2850 3500);
FORCEPROP 2 LAST PATH I4
J 0
(3300 3550);
DISPLAY 1.021277 (3300 3550);
PAINT ORANGE (3300 3550);
DISPLAY INVISIBLE (3300 3550);
FORCEPROP 2 LAST BOM_COST DEBUG
J 0
(3225 3550);
DISPLAY 1.617021 (3225 3550);
PAINT WHITE (3225 3550);
DISPLAY INVISIBLE (3225 3550);
FORCEPROP 2 LAST ROOM CPU_XDP_DEBUG
J 0
(3225 3550);
DISPLAY 1.617021 (3225 3550);
PAINT WHITE (3225 3550);
DISPLAY INVISIBLE (3225 3550);
FORCEPROP 1 LAST OFFPAGE TRUE
J 0
(3175 3375);
PAINT GREEN (3175 3375);
DISPLAY INVISIBLE (3175 3375);
FORCEPROP 1 LAST COMMENT_BODY TRUE
J 0
(2805 3405);
DISPLAY 1.893617 (2805 3405);
PAINT PEACH (2805 3405);
DISPLAY INVISIBLE (2805 3405);
FORCEADD OFFPAGE..5
(-1175 3650);
FORCEPROP 2 LAST $XR1 190 
J 0
(-1550 3650);
DISPLAY 0.638298 (-1550 3650);
PAINT MONO (-1550 3650);
FORCEPROP 2 LAST $XR0 111 
J 0
(-1430 3650);
DISPLAY 0.638298 (-1430 3650);
PAINT MONO (-1430 3650);
FORCEPROP 2 LAST BOM_COST DEBUG
J 0
(-1425 3700);
DISPLAY 1.617021 (-1425 3700);
PAINT WHITE (-1425 3700);
DISPLAY INVISIBLE (-1425 3700);
FORCEPROP 2 LAST PATH I46
J 0
(-1425 3700);
DISPLAY 1.021277 (-1425 3700);
PAINT ORANGE (-1425 3700);
DISPLAY INVISIBLE (-1425 3700);
FORCEPROP 2 LAST ROOM CPU_XDP_DEBUG
J 0
(-1425 3700);
DISPLAY 1.617021 (-1425 3700);
PAINT WHITE (-1425 3700);
DISPLAY INVISIBLE (-1425 3700);
FORCEPROP 2 LAST CDS_LIB mstr_standard
J 0
(-1175 3650);
DISPLAY 2.212766 (-1175 3650);
PAINT ORANGE (-1175 3650);
DISPLAY INVISIBLE (-1175 3650);
FORCEPROP 1 LAST OFFPAGE TRUE
J 0
(-850 3525);
PAINT GREEN (-850 3525);
DISPLAY INVISIBLE (-850 3525);
FORCEPROP 1 LAST COMMENT_BODY TRUE
J 0
(-1075 3575);
DISPLAY 1.893617 (-1075 3575);
PAINT PEACH (-1075 3575);
DISPLAY INVISIBLE (-1075 3575);
FORCEADD OFFPAGE..5
(-1175 3550);
FORCEPROP 2 LAST $XR4 56 
J 0
(-1850 3550);
DISPLAY 0.638298 (-1850 3550);
PAINT MONO (-1850 3550);
FORCEPROP 2 LAST $XR3 22 
J 0
(-1760 3550);
DISPLAY 0.638298 (-1760 3550);
PAINT MONO (-1760 3550);
FORCEPROP 2 LAST $XR2 254 
J 0
(-1670 3550);
DISPLAY 0.638298 (-1670 3550);
PAINT MONO (-1670 3550);
FORCEPROP 2 LAST $XR1 118 
J 0
(-1550 3550);
DISPLAY 0.638298 (-1550 3550);
PAINT MONO (-1550 3550);
FORCEPROP 2 LAST $XR0 111 
J 0
(-1430 3550);
DISPLAY 0.638298 (-1430 3550);
PAINT MONO (-1430 3550);
FORCEPROP 2 LAST CDS_LIB mstr_standard
J 0
(-1175 3550);
DISPLAY 2.212766 (-1175 3550);
PAINT ORANGE (-1175 3550);
DISPLAY INVISIBLE (-1175 3550);
FORCEPROP 2 LAST ROOM CPU_XDP_DEBUG
J 0
(-1375 3600);
DISPLAY 1.617021 (-1375 3600);
PAINT WHITE (-1375 3600);
DISPLAY INVISIBLE (-1375 3600);
FORCEPROP 2 LAST BOM_COST DEBUG
J 0
(-1375 3600);
DISPLAY 1.617021 (-1375 3600);
PAINT WHITE (-1375 3600);
DISPLAY INVISIBLE (-1375 3600);
FORCEPROP 2 LAST PATH I47
J 0
(-1425 3600);
DISPLAY 1.021277 (-1425 3600);
PAINT ORANGE (-1425 3600);
DISPLAY INVISIBLE (-1425 3600);
FORCEPROP 1 LAST OFFPAGE TRUE
J 0
(-850 3425);
PAINT GREEN (-850 3425);
DISPLAY INVISIBLE (-850 3425);
FORCEPROP 1 LAST COMMENT_BODY TRUE
J 0
(-1075 3475);
DISPLAY 1.893617 (-1075 3475);
PAINT PEACH (-1075 3475);
DISPLAY INVISIBLE (-1075 3475);
FORCEADD OFFPAGE..5
(-1175 3500);
FORCEPROP 2 LAST $XR2 190 
J 0
(-1670 3500);
DISPLAY 0.638298 (-1670 3500);
PAINT MONO (-1670 3500);
FORCEPROP 2 LAST $XR1 144 
J 0
(-1550 3500);
DISPLAY 0.638298 (-1550 3500);
PAINT MONO (-1550 3500);
FORCEPROP 2 LAST $XR0 111 
J 0
(-1430 3500);
DISPLAY 0.638298 (-1430 3500);
PAINT MONO (-1430 3500);
FORCEPROP 2 LAST PATH I48
J 0
(-1425 3550);
DISPLAY 1.021277 (-1425 3550);
PAINT ORANGE (-1425 3550);
DISPLAY INVISIBLE (-1425 3550);
FORCEPROP 2 LAST BOM_COST DEBUG
J 0
(-1425 3550);
DISPLAY 1.617021 (-1425 3550);
PAINT WHITE (-1425 3550);
DISPLAY INVISIBLE (-1425 3550);
FORCEPROP 2 LAST ROOM CPU_XDP_DEBUG
J 0
(-1425 3550);
DISPLAY 1.617021 (-1425 3550);
PAINT WHITE (-1425 3550);
DISPLAY INVISIBLE (-1425 3550);
FORCEPROP 2 LAST CDS_LIB mstr_standard
J 0
(-1175 3500);
DISPLAY 2.212766 (-1175 3500);
PAINT ORANGE (-1175 3500);
DISPLAY INVISIBLE (-1175 3500);
FORCEPROP 1 LAST OFFPAGE TRUE
J 0
(-850 3375);
PAINT GREEN (-850 3375);
DISPLAY INVISIBLE (-850 3375);
FORCEPROP 1 LAST COMMENT_BODY TRUE
J 0
(-1075 3425);
DISPLAY 1.893617 (-1075 3425);
PAINT PEACH (-1075 3425);
DISPLAY INVISIBLE (-1075 3425);
FORCEADD OFFPAGE..3
R 2
(-1175 3400);
FORCEPROP 2 LAST $XR5 247 
J 0
(-2055 3400);
DISPLAY 0.638298 (-2055 3400);
PAINT MONO (-2055 3400);
FORCEPROP 2 LAST $XR4 159 
J 0
(-1935 3400);
DISPLAY 0.638298 (-1935 3400);
PAINT MONO (-1935 3400);
FORCEPROP 2 LAST $XR3 156 
J 0
(-1815 3400);
DISPLAY 0.638298 (-1815 3400);
PAINT MONO (-1815 3400);
FORCEPROP 2 LAST $XR2 138 
J 0
(-1695 3400);
DISPLAY 0.638298 (-1695 3400);
PAINT MONO (-1695 3400);
FORCEPROP 2 LAST $XR1 102 
J 0
(-1575 3400);
DISPLAY 0.638298 (-1575 3400);
PAINT MONO (-1575 3400);
FORCEPROP 2 LAST $XR0 101 
J 0
(-1455 3400);
DISPLAY 0.638298 (-1455 3400);
PAINT MONO (-1455 3400);
FORCEPROP 2 LAST BOM_COST MEM_VRD_B*
J 2
(-1650 3475);
DISPLAY 1.617021 (-1650 3475);
PAINT WHITE (-1650 3475);
DISPLAY INVISIBLE (-1650 3475);
FORCEPROP 2 LAST PATH I49
J 0
(-1450 3450);
DISPLAY 1.021277 (-1450 3450);
PAINT ORANGE (-1450 3450);
DISPLAY INVISIBLE (-1450 3450);
FORCEPROP 2 LAST CDS_LIB mstr_standard
J 2
(-1175 3400);
DISPLAY 1.617021 (-1175 3400);
PAINT ORANGE (-1175 3400);
DISPLAY INVISIBLE (-1175 3400);
FORCEPROP 2 LAST ROOM VDDQ_AB_VR
J 2
(-775 3475);
DISPLAY 1.212766 (-775 3475);
PAINT WHITE (-775 3475);
DISPLAY INVISIBLE (-775 3475);
FORCEPROP 1 LAST OFFPAGE TRUE
J 2
(-1500 3275);
PAINT GREEN (-1500 3275);
DISPLAY INVISIBLE (-1500 3275);
FORCEPROP 1 LAST COMMENT_BODY TRUE
J 2
(-1125 3300);
DISPLAY 1.042553 (-1125 3300);
PAINT PEACH (-1125 3300);
DISPLAY INVISIBLE (-1125 3300);
FORCEADD OFFPAGE..5
(-1175 3300);
FORCEPROP 2 LAST $XR2 118 
J 0
(-1670 3300);
DISPLAY 0.638298 (-1670 3300);
PAINT MONO (-1670 3300);
FORCEPROP 2 LAST $XR1 112 
J 0
(-1550 3300);
DISPLAY 0.638298 (-1550 3300);
PAINT MONO (-1550 3300);
FORCEPROP 2 LAST $XR0 254 
J 0
(-1430 3300);
DISPLAY 0.638298 (-1430 3300);
PAINT MONO (-1430 3300);
FORCEPROP 2 LAST PATH I50
J 0
(-1425 3350);
DISPLAY 1.021277 (-1425 3350);
PAINT ORANGE (-1425 3350);
DISPLAY INVISIBLE (-1425 3350);
FORCEPROP 2 LAST BOM_COST DEBUG
J 0
(-1375 3350);
DISPLAY 1.617021 (-1375 3350);
PAINT WHITE (-1375 3350);
DISPLAY INVISIBLE (-1375 3350);
FORCEPROP 2 LAST ROOM CPU_XDP_DEBUG
J 0
(-1375 3350);
DISPLAY 1.617021 (-1375 3350);
PAINT WHITE (-1375 3350);
DISPLAY INVISIBLE (-1375 3350);
FORCEPROP 2 LAST CDS_LIB mstr_standard
J 0
(-1175 3300);
DISPLAY 1.617021 (-1175 3300);
PAINT ORANGE (-1175 3300);
DISPLAY INVISIBLE (-1175 3300);
FORCEPROP 1 LAST OFFPAGE TRUE
J 0
(-850 3175);
PAINT GREEN (-850 3175);
DISPLAY INVISIBLE (-850 3175);
FORCEPROP 1 LAST COMMENT_BODY TRUE
J 0
(-1075 3225);
DISPLAY 1.893617 (-1075 3225);
PAINT PEACH (-1075 3225);
DISPLAY INVISIBLE (-1075 3225);
FORCEADD OFFPAGE..1
(-1175 3350);
FORCEPROP 2 LAST $XR5 247 
J 0
(-2057 3350);
DISPLAY 0.638298 (-2057 3350);
PAINT MONO (-2057 3350);
FORCEPROP 2 LAST $XR4 156 
J 0
(-1937 3350);
DISPLAY 0.638298 (-1937 3350);
PAINT MONO (-1937 3350);
FORCEPROP 2 LAST $XR3 102 
J 0
(-1817 3350);
DISPLAY 0.638298 (-1817 3350);
PAINT MONO (-1817 3350);
FORCEPROP 2 LAST $XR2 101 
J 0
(-1697 3350);
DISPLAY 0.638298 (-1697 3350);
PAINT MONO (-1697 3350);
FORCEPROP 2 LAST $XR1 159 
J 0
(-1577 3350);
DISPLAY 0.638298 (-1577 3350);
PAINT MONO (-1577 3350);
FORCEPROP 2 LAST $XR0 138 
J 0
(-1457 3350);
DISPLAY 0.638298 (-1457 3350);
PAINT MONO (-1457 3350);
FORCEPROP 2 LAST PATH I51
J 0
(-1450 3400);
DISPLAY 1.021277 (-1450 3400);
PAINT ORANGE (-1450 3400);
DISPLAY INVISIBLE (-1450 3400);
FORCEPROP 2 LAST BOM_COST DEBUG
J 0
(-1425 3400);
DISPLAY 1.617021 (-1425 3400);
PAINT WHITE (-1425 3400);
DISPLAY INVISIBLE (-1425 3400);
FORCEPROP 2 LAST ROOM CPU_XDP_DEBUG
J 0
(-1425 3400);
DISPLAY 1.617021 (-1425 3400);
PAINT WHITE (-1425 3400);
DISPLAY INVISIBLE (-1425 3400);
FORCEPROP 2 LAST CDS_LIB mstr_standard
J 0
(-1175 3350);
DISPLAY 2.212766 (-1175 3350);
PAINT ORANGE (-1175 3350);
DISPLAY INVISIBLE (-1175 3350);
FORCEPROP 1 LAST OFFPAGE TRUE
J 0
(-850 3225);
PAINT GREEN (-850 3225);
DISPLAY INVISIBLE (-850 3225);
FORCEPROP 1 LAST COMMENT_BODY TRUE
J 0
(-1050 3250);
DISPLAY 1.893617 (-1050 3250);
PAINT PEACH (-1050 3250);
DISPLAY INVISIBLE (-1050 3250);
FORCEADD OFFPAGE..5
(-1175 3250);
FORCEPROP 2 LAST $XR3 112 
J 0
(-1730 3250);
DISPLAY 0.638298 (-1730 3250);
PAINT MONO (-1730 3250);
FORCEPROP 2 LAST $XR2 55 
J 0
(-1610 3250);
DISPLAY 0.638298 (-1610 3250);
PAINT MONO (-1610 3250);
FORCEPROP 2 LAST $XR1 21 
J 0
(-1520 3250);
DISPLAY 0.638298 (-1520 3250);
PAINT MONO (-1520 3250);
FORCEPROP 2 LAST $XR0 254 
J 0
(-1430 3250);
DISPLAY 0.638298 (-1430 3250);
PAINT MONO (-1430 3250);
FORCEPROP 2 LAST PATH I52
J 0
(-1425 3300);
DISPLAY 1.021277 (-1425 3300);
PAINT ORANGE (-1425 3300);
DISPLAY INVISIBLE (-1425 3300);
FORCEPROP 2 LAST BOM_COST DEBUG
J 0
(-1375 3300);
DISPLAY 1.617021 (-1375 3300);
PAINT WHITE (-1375 3300);
DISPLAY INVISIBLE (-1375 3300);
FORCEPROP 2 LAST ROOM CPU_XDP_DEBUG
J 0
(-1375 3300);
DISPLAY 1.617021 (-1375 3300);
PAINT WHITE (-1375 3300);
DISPLAY INVISIBLE (-1375 3300);
FORCEPROP 2 LAST CDS_LIB mstr_standard
J 0
(-1175 3250);
DISPLAY 2.212766 (-1175 3250);
PAINT ORANGE (-1175 3250);
DISPLAY INVISIBLE (-1175 3250);
FORCEPROP 1 LAST OFFPAGE TRUE
J 0
(-850 3125);
PAINT GREEN (-850 3125);
DISPLAY INVISIBLE (-850 3125);
FORCEPROP 1 LAST COMMENT_BODY TRUE
J 0
(-1075 3175);
DISPLAY 1.893617 (-1075 3175);
PAINT PEACH (-1075 3175);
DISPLAY INVISIBLE (-1075 3175);
FORCEADD PVCCIO_CPU0..1
(-850 1600);
FORCEPROP 3 LASTPIN (-850 1550) SIG_NAME PVCCIO_CPU0\g
J 0
(-840 1560);
DISPLAY 0.659574 (-840 1560);
PAINT MONO (-840 1560);
DISPLAY INVISIBLE (-840 1560);
FORCEPROP 1 LAST PATH I54
J 0
(-800 1625);
DISPLAY 0.872340 (-800 1625);
PAINT AQUA (-800 1625);
DISPLAY INVISIBLE (-800 1625);
FORCEPROP 2 LAST CDS_LIB mstr_symbols
J 0
(-850 1600);
PAINT ORANGE (-850 1600);
DISPLAY INVISIBLE (-850 1600);
FORCEPROP 1 LAST VOLTAGE 1.1V
J 0
(-895 1557);
DISPLAY 0.340426 (-895 1557);
PAINT SKYBLUE (-895 1557);
DISPLAY INVISIBLE (-895 1557);
FORCEPROP 1 LAST BODY_TYPE PLUMBING
J 0
(-895 1557);
DISPLAY 0.340426 (-895 1557);
PAINT GREEN (-895 1557);
DISPLAY INVISIBLE (-895 1557);
FORCEPROP 1 LAST HDL_POWER PVCCIO_CPU0
J 1
(-850 1650);
DISPLAY 0.872340 (-850 1650);
PAINT GREEN (-850 1650);
DISPLAY INVISIBLE (-850 1650);
FORCEADD RES..1
(-1400 1450);
FORCEPROP 1 LASTPIN (-1300 1450) $PN 2
J 0
(-1338 1462);
DISPLAY 0.617021 (-1338 1462);
PAINT WHITE (-1338 1462);
FORCEPROP 1 LAST PACK_TYPE 0402
J 0
(-1250 1400);
DISPLAY 0.617021 (-1250 1400);
PAINT SKYBLUE (-1250 1400);
FORCEPROP 1 LASTPIN (-1500 1450) $PN 1
J 0
(-1488 1462);
DISPLAY 0.617021 (-1488 1462);
PAINT WHITE (-1488 1462);
FORCEPROP 1 LAST LOCATION R9A4
J 0
(-1450 1500);
DISPLAY 0.617021 (-1450 1500);
PAINT AQUA (-1450 1500);
FORCEPROP 1 LAST MATERIAL CHIP
J 0
(-1400 1350);
DISPLAY 0.617021 (-1400 1350);
PAINT SKYBLUE (-1400 1350);
FORCEPROP 1 LAST PART_NUMBER G21796-077
J 0
(-1250 1475);
DISPLAY 0.617021 (-1250 1475);
PAINT BLUE (-1250 1475);
FORCEPROP 1 LAST TOLERANCE 1%
J 0
(-1400 1400);
DISPLAY 0.617021 (-1400 1400);
PAINT SKYBLUE (-1400 1400);
FORCEPROP 1 LAST WATTAGE 1/16W
J 2
(-1425 1350);
DISPLAY 0.617021 (-1425 1350);
PAINT SKYBLUE (-1425 1350);
FORCEPROP 1 LAST VALUE 475.0
J 2
(-1425 1400);
DISPLAY 0.617021 (-1425 1400);
PAINT SKYBLUE (-1425 1400);
FORCEPROP 2 LAST CDS_LOCATION R9A4
J 0
(-1450 1500);
DISPLAY 0.617021 (-1450 1500);
PAINT AQUA (-1450 1500);
DISPLAY INVISIBLE (-1450 1500);
FORCEPROP 2 LAST CDS_LIB mstr_discrete
J 0
(-1400 1450);
DISPLAY 2.212766 (-1400 1450);
PAINT ORANGE (-1400 1450);
DISPLAY INVISIBLE (-1400 1450);
FORCEPROP 2 LAST BOM_COST DEBUG
J 0
(-1450 1550);
DISPLAY 1.617021 (-1450 1550);
PAINT WHITE (-1450 1550);
DISPLAY INVISIBLE (-1450 1550);
FORCEPROP 2 LAST SEC_TYPE 0402
J 0
(-1450 1550);
DISPLAY 1.659574 (-1450 1550);
PAINT ORANGE (-1450 1550);
DISPLAY INVISIBLE (-1450 1550);
FORCEPROP 2 LAST ROOM DEBUG
J 0
(-1450 1600);
DISPLAY 1.617021 (-1450 1600);
PAINT WHITE (-1450 1600);
DISPLAY INVISIBLE (-1450 1600);
FORCEPROP 2 LAST SEC 1
J 0
(-1450 1650);
DISPLAY 1.510638 (-1450 1650);
PAINT MONO (-1450 1650);
DISPLAY INVISIBLE (-1450 1650);
FORCEPROP 1 LAST PATH I55
J 0
(-1450 1600);
DISPLAY 0.978723 (-1450 1600);
PAINT WHITE (-1450 1600);
DISPLAY INVISIBLE (-1450 1600);
FORCEADD RES..1
(-1400 1100);
FORCEPROP 1 LASTPIN (-1500 1100) $PN 1
J 0
(-1488 1112);
DISPLAY 0.617021 (-1488 1112);
PAINT WHITE (-1488 1112);
FORCEPROP 1 LAST WATTAGE 1/16W
J 2
(-1425 1000);
DISPLAY 0.617021 (-1425 1000);
PAINT SKYBLUE (-1425 1000);
FORCEPROP 1 LAST TOLERANCE 1%
J 0
(-1400 1050);
DISPLAY 0.617021 (-1400 1050);
PAINT SKYBLUE (-1400 1050);
FORCEPROP 1 LAST MATERIAL CHIP
J 0
(-1400 1000);
DISPLAY 0.617021 (-1400 1000);
PAINT SKYBLUE (-1400 1000);
FORCEPROP 1 LASTPIN (-1300 1100) $PN 2
J 0
(-1338 1112);
DISPLAY 0.617021 (-1338 1112);
PAINT WHITE (-1338 1112);
FORCEPROP 1 LAST LOCATION R1L17
J 0
(-1450 1150);
DISPLAY 0.617021 (-1450 1150);
PAINT AQUA (-1450 1150);
FORCEPROP 1 LAST PART_NUMBER G21796-009
J 0
(-1250 1125);
DISPLAY 0.617021 (-1250 1125);
PAINT BLUE (-1250 1125);
FORCEPROP 1 LAST PACK_TYPE 0402
J 0
(-1250 1050);
DISPLAY 0.617021 (-1250 1050);
PAINT SKYBLUE (-1250 1050);
FORCEPROP 1 LAST VALUE 150.0
J 2
(-1425 1050);
DISPLAY 0.617021 (-1425 1050);
PAINT SKYBLUE (-1425 1050);
FORCEPROP 2 LAST SEC 1
J 0
(-1450 1300);
DISPLAY 1.510638 (-1450 1300);
PAINT MONO (-1450 1300);
DISPLAY INVISIBLE (-1450 1300);
FORCEPROP 1 LAST PATH I56
J 0
(-1450 1250);
DISPLAY 0.978723 (-1450 1250);
PAINT WHITE (-1450 1250);
DISPLAY INVISIBLE (-1450 1250);
FORCEPROP 2 LAST ROOM DEBUG
J 0
(-1450 1250);
DISPLAY 1.617021 (-1450 1250);
PAINT WHITE (-1450 1250);
DISPLAY INVISIBLE (-1450 1250);
FORCEPROP 2 LAST CDS_LIB mstr_discrete
J 0
(-1400 1100);
DISPLAY 2.212766 (-1400 1100);
PAINT ORANGE (-1400 1100);
DISPLAY INVISIBLE (-1400 1100);
FORCEPROP 2 LAST BOM_COST DEBUG
J 0
(-1450 1200);
DISPLAY 1.617021 (-1450 1200);
PAINT WHITE (-1450 1200);
DISPLAY INVISIBLE (-1450 1200);
FORCEPROP 2 LAST SEC_TYPE 0402
J 0
(-1450 1200);
DISPLAY 1.659574 (-1450 1200);
PAINT ORANGE (-1450 1200);
DISPLAY INVISIBLE (-1450 1200);
FORCEPROP 2 LAST CDS_LOCATION R1L17
J 0
(-1450 1150);
DISPLAY 0.617021 (-1450 1150);
PAINT AQUA (-1450 1150);
DISPLAY INVISIBLE (-1450 1150);
FORCEADD RES..1
(-1400 500);
FORCEPROP 1 LAST TOLERANCE 1%
J 0
(-1375 450);
DISPLAY 0.617021 (-1375 450);
PAINT SKYBLUE (-1375 450);
FORCEPROP 1 LASTPIN (-1300 500) $PN 2
J 0
(-1338 512);
DISPLAY 0.617021 (-1338 512);
PAINT WHITE (-1338 512);
FORCEPROP 1 LAST LOCATION R9A17
J 0
(-1450 550);
DISPLAY 0.617021 (-1450 550);
PAINT AQUA (-1450 550);
FORCEPROP 1 LAST WATTAGE 1/16W
J 2
(-1425 400);
DISPLAY 0.617021 (-1425 400);
PAINT SKYBLUE (-1425 400);
FORCEPROP 1 LASTPIN (-1500 500) $PN 1
J 0
(-1488 512);
DISPLAY 0.617021 (-1488 512);
PAINT WHITE (-1488 512);
FORCEPROP 1 LAST VALUE 1.00K
J 2
(-1425 450);
DISPLAY 0.617021 (-1425 450);
PAINT SKYBLUE (-1425 450);
FORCEPROP 1 LAST MATERIAL CHIP
J 0
(-1400 400);
DISPLAY 0.617021 (-1400 400);
PAINT SKYBLUE (-1400 400);
FORCEPROP 1 LAST PACK_TYPE 0402
J 0
(-1250 450);
DISPLAY 0.617021 (-1250 450);
PAINT SKYBLUE (-1250 450);
FORCEPROP 1 LAST PART_NUMBER G21796-026
J 0
(-1250 525);
DISPLAY 0.617021 (-1250 525);
PAINT BLUE (-1250 525);
FORCEPROP 2 LAST CDS_LIB mstr_discrete
J 0
(-1400 500);
DISPLAY 1.617021 (-1400 500);
PAINT MONO (-1400 500);
DISPLAY INVISIBLE (-1400 500);
FORCEPROP 2 LAST ROOM DEBUG
J 0
(-1450 650);
DISPLAY 1.617021 (-1450 650);
PAINT WHITE (-1450 650);
DISPLAY INVISIBLE (-1450 650);
FORCEPROP 2 LAST BOM_COST DEBUG
J 0
(-1450 600);
DISPLAY 1.617021 (-1450 600);
PAINT WHITE (-1450 600);
DISPLAY INVISIBLE (-1450 600);
FORCEPROP 2 LAST SEC_TYPE 0402
J 0
(-1450 600);
DISPLAY 1.659574 (-1450 600);
PAINT ORANGE (-1450 600);
DISPLAY INVISIBLE (-1450 600);
FORCEPROP 1 LAST PATH I57
J 0
(-1450 650);
DISPLAY 0.978723 (-1450 650);
PAINT WHITE (-1450 650);
DISPLAY INVISIBLE (-1450 650);
FORCEPROP 2 LAST CDS_LOCATION R9A17
J 0
(-1450 550);
DISPLAY 0.617021 (-1450 550);
PAINT AQUA (-1450 550);
DISPLAY INVISIBLE (-1450 550);
FORCEPROP 2 LAST SEC 1
J 0
(-1450 700);
DISPLAY 1.510638 (-1450 700);
PAINT MONO (-1450 700);
DISPLAY INVISIBLE (-1450 700);
FORCEADD GND..1
(-1100 800);
FORCEPROP 3 LASTPIN (-1100 850) SIG_NAME GND\g
J 0
(-1090 860);
DISPLAY 0.659574 (-1090 860);
PAINT MONO (-1090 860);
DISPLAY INVISIBLE (-1090 860);
FORCEPROP 2 LAST CDS_LIB mstr_symbols
J 0
(-1100 800);
DISPLAY 2.212766 (-1100 800);
PAINT ORANGE (-1100 800);
DISPLAY INVISIBLE (-1100 800);
FORCEPROP 1 LAST PATH I58
J 0
(-1025 800);
DISPLAY 0.872340 (-1025 800);
PAINT AQUA (-1025 800);
DISPLAY INVISIBLE (-1025 800);
FORCEPROP 1 LAST VOLTAGE 0.0V
J 0
(-1145 757);
DISPLAY 0.340426 (-1145 757);
PAINT SKYBLUE (-1145 757);
DISPLAY INVISIBLE (-1145 757);
FORCEPROP 1 LAST SIZE 1B
J 0
(-1025 750);
DISPLAY 1.893617 (-1025 750);
PAINT GREEN (-1025 750);
DISPLAY INVISIBLE (-1025 750);
FORCEPROP 2 LAST BOM_COST DEBUG
J 0
(-1250 875);
DISPLAY 1.617021 (-1250 875);
PAINT WHITE (-1250 875);
DISPLAY INVISIBLE (-1250 875);
FORCEPROP 2 LAST ROOM CPU_XDP_DEBUG
J 0
(-1550 875);
DISPLAY 1.617021 (-1550 875);
PAINT WHITE (-1550 875);
DISPLAY INVISIBLE (-1550 875);
FORCEPROP 1 LAST BODY_TYPE PLUMBING
J 0
(-1145 757);
DISPLAY 0.340426 (-1145 757);
PAINT GREEN (-1145 757);
DISPLAY INVISIBLE (-1145 757);
FORCEPROP 1 LAST HDL_POWER GND
J 0
(-1100 950);
PAINT GREEN (-1100 950);
DISPLAY INVISIBLE (-1100 950);
FORCEADD CAP_A..1
R 1
(-1400 875);
FORCEPROP 1 LAST PACK_TYPE 0402V
J 0
(-1150 900);
DISPLAY 0.617021 (-1150 900);
PAINT SKYBLUE (-1150 900);
FORCEPROP 1 LAST MATERIAL X7R
J 0
(-1275 900);
DISPLAY 0.617021 (-1275 900);
PAINT SKYBLUE (-1275 900);
FORCEPROP 1 LAST VALUE 0.1UF
J 0
(-1750 900);
DISPLAY 0.617021 (-1750 900);
PAINT SKYBLUE (-1750 900);
FORCEPROP 1 LASTPIN (-1300 875) $PN 2
J 0
(-1355 885);
DISPLAY 0.617021 (-1355 885);
PAINT WHITE (-1355 885);
FORCEPROP 1 LAST LOCATION C9A4
J 0
(-1400 950);
DISPLAY 0.617021 (-1400 950);
PAINT AQUA (-1400 950);
FORCEPROP 1 LASTPIN (-1500 875) $PN 1
J 0
(-1455 885);
DISPLAY 0.617021 (-1455 885);
PAINT WHITE (-1455 885);
FORCEPROP 1 LAST VOLTAGE 16V
J 0
(-1625 900);
DISPLAY 0.617021 (-1625 900);
PAINT SKYBLUE (-1625 900);
FORCEPROP 1 LAST TOLERANCE 10%
J 0
(-1550 900);
DISPLAY 0.617021 (-1550 900);
PAINT SKYBLUE (-1550 900);
FORCEPROP 1 LAST PART_NUMBER A36096-030
J 0
(-1525 775);
DISPLAY 0.617021 (-1525 775);
PAINT BLUE (-1525 775);
FORCEPROP 2 LAST SEC 1
J 0
(-1400 1000);
DISPLAY 1.510638 (-1400 1000);
PAINT MONO (-1400 1000);
DISPLAY INVISIBLE (-1400 1000);
FORCEPROP 2 LAST BOM_COST DEBUG
J 0
(-1400 1000);
DISPLAY 1.617021 (-1400 1000);
PAINT WHITE (-1400 1000);
DISPLAY INVISIBLE (-1400 1000);
FORCEPROP 2 LAST ROOM DEBUG
J 0
(-1400 1000);
DISPLAY 1.617021 (-1400 1000);
PAINT WHITE (-1400 1000);
DISPLAY INVISIBLE (-1400 1000);
FORCEPROP 2 LAST CDS_SEC 1
R 1
J 0
(-1400 1000);
PAINT ORANGE (-1400 1000);
DISPLAY INVISIBLE (-1400 1000);
FORCEPROP 2 LAST CDS_LIB dev_discrete
J 0
(-1400 875);
PAINT ORANGE (-1400 875);
DISPLAY INVISIBLE (-1400 875);
FORCEPROP 2 LAST CDS_LOCATION C9A4
J 0
(-1400 950);
DISPLAY 0.617021 (-1400 950);
PAINT AQUA (-1400 950);
DISPLAY INVISIBLE (-1400 950);
FORCEPROP 2 LAST SEC_TYPE 0402V
R 1
J 0
(-1400 1000);
DISPLAY 1.659574 (-1400 1000);
PAINT ORANGE (-1400 1000);
DISPLAY INVISIBLE (-1400 1000);
FORCEPROP 1 LAST PATH I59
R 1
J 0
(-1550 925);
DISPLAY 0.978723 (-1550 925);
PAINT WHITE (-1550 925);
DISPLAY INVISIBLE (-1550 925);
FORCEADD RES..1
(2725 2150);
FORCEPROP 1 LAST PART_NUMBER G21796-026
J 0
(2850 2175);
DISPLAY 0.617021 (2850 2175);
PAINT BLUE (2850 2175);
FORCEPROP 1 LAST TOLERANCE 1%
J 0
(2725 2100);
DISPLAY 0.617021 (2725 2100);
PAINT SKYBLUE (2725 2100);
FORCEPROP 1 LASTPIN (2625 2150) $PN 1
J 0
(2637 2162);
DISPLAY 0.617021 (2637 2162);
PAINT WHITE (2637 2162);
FORCEPROP 1 LASTPIN (2825 2150) $PN 2
J 0
(2787 2162);
DISPLAY 0.617021 (2787 2162);
PAINT WHITE (2787 2162);
FORCEPROP 1 LAST LOCATION R1L13
J 0
(2675 2200);
DISPLAY 0.617021 (2675 2200);
PAINT AQUA (2675 2200);
FORCEPROP 1 LAST PACK_TYPE 0402
J 0
(2850 2100);
DISPLAY 0.617021 (2850 2100);
PAINT SKYBLUE (2850 2100);
FORCEPROP 1 LAST MATERIAL CHIP
J 0
(2975 2100);
DISPLAY 0.617021 (2975 2100);
PAINT SKYBLUE (2975 2100);
FORCEPROP 1 LAST WATTAGE 1/16W
J 2
(2700 2100);
DISPLAY 0.617021 (2700 2100);
PAINT SKYBLUE (2700 2100);
FORCEPROP 1 LAST VALUE 1.00K
J 2
(2575 2100);
DISPLAY 0.617021 (2575 2100);
PAINT SKYBLUE (2575 2100);
FORCEPROP 2 LAST CDS_LIB mstr_discrete
J 0
(2725 2150);
DISPLAY 2.212766 (2725 2150);
PAINT ORANGE (2725 2150);
DISPLAY INVISIBLE (2725 2150);
FORCEPROP 2 LAST CDS_LOCATION R1L13
J 0
(2675 2200);
DISPLAY 0.617021 (2675 2200);
PAINT AQUA (2675 2200);
DISPLAY INVISIBLE (2675 2200);
FORCEPROP 2 LAST BOM_COST DEBUG
J 0
(2675 2250);
DISPLAY 1.617021 (2675 2250);
PAINT WHITE (2675 2250);
DISPLAY INVISIBLE (2675 2250);
FORCEPROP 2 LAST SEC_TYPE 0402
J 0
(2675 2250);
DISPLAY 1.659574 (2675 2250);
PAINT ORANGE (2675 2250);
DISPLAY INVISIBLE (2675 2250);
FORCEPROP 1 LAST PATH I6
J 0
(2675 2300);
DISPLAY 0.978723 (2675 2300);
PAINT WHITE (2675 2300);
DISPLAY INVISIBLE (2675 2300);
FORCEPROP 2 LAST ROOM DEBUG
J 0
(2675 2300);
DISPLAY 1.617021 (2675 2300);
PAINT WHITE (2675 2300);
DISPLAY INVISIBLE (2675 2300);
FORCEPROP 2 LAST SEC 1
J 0
(2675 2350);
DISPLAY 1.510638 (2675 2350);
PAINT MONO (2675 2350);
DISPLAY INVISIBLE (2675 2350);
FORCEADD RES..1
(-2175 3700);
FORCEPROP 1 LASTPIN (-2275 3700) $PN 1
J 0
(-2263 3712);
DISPLAY 0.617021 (-2263 3712);
PAINT WHITE (-2263 3712);
FORCEPROP 1 LASTPIN (-2075 3700) $PN 2
J 0
(-2113 3712);
DISPLAY 0.617021 (-2113 3712);
PAINT WHITE (-2113 3712);
FORCEPROP 1 LAST PACK_TYPE 0402
J 0
(-2125 3650);
DISPLAY 0.617021 (-2125 3650);
PAINT SKYBLUE (-2125 3650);
FORCEPROP 1 LAST MATERIAL CHIP
J 0
(-2075 3600);
DISPLAY 0.617021 (-2075 3600);
PAINT SKYBLUE (-2075 3600);
FORCEPROP 1 LAST LOCATION R9A15
J 0
(-2225 3750);
DISPLAY 0.617021 (-2225 3750);
PAINT AQUA (-2225 3750);
FORCEPROP 1 LAST PART_NUMBER G21796-026
J 0
(-2475 3650);
DISPLAY 0.617021 (-2475 3650);
PAINT BLUE (-2475 3650);
FORCEPROP 1 LAST WATTAGE 1/16W
J 2
(-2150 3600);
DISPLAY 0.617021 (-2150 3600);
PAINT SKYBLUE (-2150 3600);
FORCEPROP 1 LAST TOLERANCE 1%
J 0
(-2375 3600);
DISPLAY 0.617021 (-2375 3600);
PAINT SKYBLUE (-2375 3600);
FORCEPROP 1 LAST VALUE 1.00K
J 2
(-2425 3600);
DISPLAY 0.617021 (-2425 3600);
PAINT SKYBLUE (-2425 3600);
FORCEPROP 2 LAST CDS_LOCATION R9A15
J 0
(-2225 3750);
DISPLAY 0.617021 (-2225 3750);
PAINT AQUA (-2225 3750);
DISPLAY INVISIBLE (-2225 3750);
FORCEPROP 2 LAST CDS_LIB mstr_discrete
J 0
(-2175 3700);
DISPLAY 2.212766 (-2175 3700);
PAINT ORANGE (-2175 3700);
DISPLAY INVISIBLE (-2175 3700);
FORCEPROP 2 LAST SEC_TYPE 0402
J 0
(-2225 3800);
DISPLAY 1.659574 (-2225 3800);
PAINT ORANGE (-2225 3800);
DISPLAY INVISIBLE (-2225 3800);
FORCEPROP 2 LAST BOM_COST DEBUG
J 0
(-2225 3800);
DISPLAY 1.617021 (-2225 3800);
PAINT WHITE (-2225 3800);
DISPLAY INVISIBLE (-2225 3800);
FORCEPROP 1 LAST PATH I60
J 0
(-2225 3850);
DISPLAY 0.978723 (-2225 3850);
PAINT WHITE (-2225 3850);
DISPLAY INVISIBLE (-2225 3850);
FORCEPROP 2 LAST SEC 1
J 0
(-2225 3900);
DISPLAY 1.510638 (-2225 3900);
PAINT MONO (-2225 3900);
DISPLAY INVISIBLE (-2225 3900);
FORCEPROP 2 LAST ROOM DEBUG
J 0
(-2225 3850);
DISPLAY 1.617021 (-2225 3850);
PAINT WHITE (-2225 3850);
DISPLAY INVISIBLE (-2225 3850);
FORCEADD OFFPAGE..1
(-2950 3700);
FORCEPROP 2 LAST $XR3 147 
J 0
(-3562 3700);
DISPLAY 0.638298 (-3562 3700);
PAINT MONO (-3562 3700);
FORCEPROP 2 LAST $XR2 118 
J 0
(-3442 3700);
DISPLAY 0.638298 (-3442 3700);
PAINT MONO (-3442 3700);
FORCEPROP 2 LAST $XR1 192 
J 0
(-3322 3700);
DISPLAY 0.638298 (-3322 3700);
PAINT MONO (-3322 3700);
FORCEPROP 2 LAST $XR0 190 
J 0
(-3202 3700);
DISPLAY 0.638298 (-3202 3700);
PAINT MONO (-3202 3700);
FORCEPROP 2 LAST PATH I61
J 0
(-3200 3750);
DISPLAY 1.021277 (-3200 3750);
PAINT ORANGE (-3200 3750);
DISPLAY INVISIBLE (-3200 3750);
FORCEPROP 2 LAST BOM_COST DEBUG
J 0
(-3150 3750);
DISPLAY 1.617021 (-3150 3750);
PAINT WHITE (-3150 3750);
DISPLAY INVISIBLE (-3150 3750);
FORCEPROP 2 LAST ROOM CPU_XDP_DEBUG
J 0
(-3150 3750);
DISPLAY 1.617021 (-3150 3750);
PAINT WHITE (-3150 3750);
DISPLAY INVISIBLE (-3150 3750);
FORCEPROP 2 LAST CDS_LIB mstr_standard
J 0
(-2950 3700);
DISPLAY 2.212766 (-2950 3700);
PAINT ORANGE (-2950 3700);
DISPLAY INVISIBLE (-2950 3700);
FORCEPROP 1 LAST OFFPAGE TRUE
J 0
(-2625 3575);
PAINT GREEN (-2625 3575);
DISPLAY INVISIBLE (-2625 3575);
FORCEPROP 1 LAST COMMENT_BODY TRUE
J 0
(-2825 3600);
DISPLAY 1.893617 (-2825 3600);
PAINT PEACH (-2825 3600);
DISPLAY INVISIBLE (-2825 3600);
FORCEADD OFFPAGE..5
(-2600 500);
FORCEPROP 2 LAST $XR1 111 
J 0
(-2975 500);
DISPLAY 0.638298 (-2975 500);
PAINT MONO (-2975 500);
FORCEPROP 2 LAST $XR0 118 
J 0
(-2855 500);
DISPLAY 0.638298 (-2855 500);
PAINT MONO (-2855 500);
FORCEPROP 2 LAST CDS_LIB mstr_standard
J 1
(-2600 500);
DISPLAY 1.617021 (-2600 500);
PAINT ORANGE (-2600 500);
DISPLAY INVISIBLE (-2600 500);
FORCEPROP 2 LAST PATH I62
J 0
(-2875 550);
DISPLAY 1.021277 (-2875 550);
PAINT ORANGE (-2875 550);
DISPLAY INVISIBLE (-2875 550);
FORCEPROP 2 LAST ROOM CPU_XDP_DEBUG
J 0
(-2800 550);
DISPLAY 1.617021 (-2800 550);
PAINT WHITE (-2800 550);
DISPLAY INVISIBLE (-2800 550);
FORCEPROP 2 LAST BOM_COST DEBUG
J 0
(-2800 550);
DISPLAY 1.617021 (-2800 550);
PAINT WHITE (-2800 550);
DISPLAY INVISIBLE (-2800 550);
FORCEPROP 1 LAST OFFPAGE TRUE
J 0
(-2275 375);
PAINT GREEN (-2275 375);
DISPLAY INVISIBLE (-2275 375);
FORCEPROP 1 LAST COMMENT_BODY TRUE
J 0
(-2500 425);
DISPLAY 1.893617 (-2500 425);
PAINT PEACH (-2500 425);
DISPLAY INVISIBLE (-2500 425);
FORCEADD OFFPAGE..5
(-2600 1450);
FORCEPROP 2 LAST $XR2 56 
J 0
(-3035 1450);
DISPLAY 0.638298 (-3035 1450);
PAINT MONO (-3035 1450);
FORCEPROP 2 LAST $XR1 22 
J 0
(-2945 1450);
DISPLAY 0.638298 (-2945 1450);
PAINT MONO (-2945 1450);
FORCEPROP 2 LAST $XR0 255 
J 0
(-2855 1450);
DISPLAY 0.638298 (-2855 1450);
PAINT MONO (-2855 1450);
FORCEPROP 2 LAST ROOM CPU_XDP_DEBUG
J 0
(-2800 1500);
DISPLAY 1.617021 (-2800 1500);
PAINT WHITE (-2800 1500);
DISPLAY INVISIBLE (-2800 1500);
FORCEPROP 2 LAST BOM_COST DEBUG
J 0
(-2800 1500);
DISPLAY 1.617021 (-2800 1500);
PAINT WHITE (-2800 1500);
DISPLAY INVISIBLE (-2800 1500);
FORCEPROP 2 LAST CDS_LIB mstr_standard
J 0
(-2600 1450);
DISPLAY 2.212766 (-2600 1450);
PAINT ORANGE (-2600 1450);
DISPLAY INVISIBLE (-2600 1450);
FORCEPROP 2 LAST PATH I63
J 0
(-2875 1500);
DISPLAY 1.021277 (-2875 1500);
PAINT ORANGE (-2875 1500);
DISPLAY INVISIBLE (-2875 1500);
FORCEPROP 1 LAST OFFPAGE TRUE
J 0
(-2275 1325);
PAINT GREEN (-2275 1325);
DISPLAY INVISIBLE (-2275 1325);
FORCEPROP 1 LAST COMMENT_BODY TRUE
J 0
(-2500 1375);
DISPLAY 1.893617 (-2500 1375);
PAINT PEACH (-2500 1375);
DISPLAY INVISIBLE (-2500 1375);
FORCEADD OFFPAGE..5
(-2600 1100);
FORCEPROP 2 LAST $XR4 56 
J 0
(-3275 1100);
DISPLAY 0.638298 (-3275 1100);
PAINT MONO (-3275 1100);
FORCEPROP 2 LAST $XR3 22 
J 0
(-3185 1100);
DISPLAY 0.638298 (-3185 1100);
PAINT MONO (-3185 1100);
FORCEPROP 2 LAST $XR2 254 
J 0
(-3095 1100);
DISPLAY 0.638298 (-3095 1100);
PAINT MONO (-3095 1100);
FORCEPROP 2 LAST $XR1 118 
J 0
(-2975 1100);
DISPLAY 0.638298 (-2975 1100);
PAINT MONO (-2975 1100);
FORCEPROP 2 LAST $XR0 111 
J 0
(-2855 1100);
DISPLAY 0.638298 (-2855 1100);
PAINT MONO (-2855 1100);
FORCEPROP 2 LAST PATH I64
J 0
(-2850 1150);
DISPLAY 1.021277 (-2850 1150);
PAINT ORANGE (-2850 1150);
DISPLAY INVISIBLE (-2850 1150);
FORCEPROP 2 LAST BOM_COST DEBUG
J 0
(-2800 1150);
DISPLAY 1.617021 (-2800 1150);
PAINT WHITE (-2800 1150);
DISPLAY INVISIBLE (-2800 1150);
FORCEPROP 2 LAST ROOM CPU_XDP_DEBUG
J 0
(-2800 1150);
DISPLAY 1.617021 (-2800 1150);
PAINT WHITE (-2800 1150);
DISPLAY INVISIBLE (-2800 1150);
FORCEPROP 2 LAST CDS_LIB mstr_standard
J 1
(-2600 1100);
DISPLAY 1.617021 (-2600 1100);
PAINT ORANGE (-2600 1100);
DISPLAY INVISIBLE (-2600 1100);
FORCEPROP 1 LAST OFFPAGE TRUE
J 0
(-2275 975);
PAINT GREEN (-2275 975);
DISPLAY INVISIBLE (-2275 975);
FORCEPROP 1 LAST COMMENT_BODY TRUE
J 0
(-2500 1025);
DISPLAY 1.893617 (-2500 1025);
PAINT PEACH (-2500 1025);
DISPLAY INVISIBLE (-2500 1025);
FORCEADD P3V3_STBY..1
(3250 2300);
FORCEPROP 3 LASTPIN (3250 2250) SIG_NAME P3V3_STBY\g
J 0
(3260 2260);
DISPLAY 0.659574 (3260 2260);
PAINT MONO (3260 2260);
DISPLAY INVISIBLE (3260 2260);
FORCEPROP 1 LAST VOLTAGE 3.3V
J 0
(3205 2257);
DISPLAY 0.340426 (3205 2257);
PAINT SKYBLUE (3205 2257);
DISPLAY INVISIBLE (3205 2257);
FORCEPROP 2 LAST CDS_LIB mstr_symbols
J 0
(3250 2300);
PAINT ORANGE (3250 2300);
DISPLAY INVISIBLE (3250 2300);
FORCEPROP 1 LAST PATH I65
J 0
(3295 2302);
DISPLAY 0.340426 (3295 2302);
PAINT GREEN (3295 2302);
DISPLAY INVISIBLE (3295 2302);
FORCEPROP 1 LAST SIZE 1B
J 0
(3295 2322);
DISPLAY 0.340426 (3295 2322);
PAINT GREEN (3295 2322);
DISPLAY INVISIBLE (3295 2322);
FORCEPROP 1 LAST BODY_TYPE PLUMBING
J 0
(3205 2257);
DISPLAY 0.340426 (3205 2257);
PAINT GREEN (3205 2257);
DISPLAY INVISIBLE (3205 2257);
FORCEPROP 1 LAST HDL_POWER P3V3_STBY
J 0
(2950 2175);
DISPLAY 0.872340 (2950 2175);
PAINT ORANGE (2950 2175);
DISPLAY INVISIBLE (2950 2175);
FORCEADD P3V3_STBY..1
(2175 2975);
FORCEPROP 3 LASTPIN (2175 2925) SIG_NAME P3V3_STBY\g
J 0
(2185 2935);
DISPLAY 0.659574 (2185 2935);
PAINT MONO (2185 2935);
DISPLAY INVISIBLE (2185 2935);
FORCEPROP 2 LAST CDS_LIB mstr_symbols
J 0
(2175 2975);
PAINT ORANGE (2175 2975);
DISPLAY INVISIBLE (2175 2975);
FORCEPROP 1 LAST VOLTAGE 3.3V
J 0
(2130 2932);
DISPLAY 0.340426 (2130 2932);
PAINT SKYBLUE (2130 2932);
DISPLAY INVISIBLE (2130 2932);
FORCEPROP 1 LAST SIZE 1B
J 0
(2220 2997);
DISPLAY 0.340426 (2220 2997);
PAINT GREEN (2220 2997);
DISPLAY INVISIBLE (2220 2997);
FORCEPROP 1 LAST PATH I67
J 0
(2220 2977);
DISPLAY 0.340426 (2220 2977);
PAINT GREEN (2220 2977);
DISPLAY INVISIBLE (2220 2977);
FORCEPROP 1 LAST BODY_TYPE PLUMBING
J 0
(2130 2932);
DISPLAY 0.340426 (2130 2932);
PAINT GREEN (2130 2932);
DISPLAY INVISIBLE (2130 2932);
FORCEPROP 1 LAST HDL_POWER P3V3_STBY
J 0
(1875 2850);
DISPLAY 0.872340 (1875 2850);
PAINT ORANGE (1875 2850);
DISPLAY INVISIBLE (1875 2850);
FORCEADD RES..1
(2950 2600);
FORCEPROP 1 LAST PACK_TYPE 0402
J 0
(3200 2450);
DISPLAY 0.617021 (3200 2450);
PAINT SKYBLUE (3200 2450);
FORCEPROP 1 LAST PART_NUMBER G21796-074
J 0
(2900 2700);
DISPLAY 0.617021 (2900 2700);
PAINT BLUE (2900 2700);
FORCEPROP 1 LASTPIN (3050 2600) $PN 2
J 0
(3012 2612);
DISPLAY 0.617021 (3012 2612);
PAINT ORANGE (3012 2612);
FORCEPROP 1 LASTPIN (2850 2600) $PN 1
J 0
(2862 2612);
DISPLAY 0.617021 (2862 2612);
PAINT ORANGE (2862 2612);
FORCEPROP 1 LAST MATERIAL CHIP
J 0
(2950 2450);
DISPLAY 0.617021 (2950 2450);
PAINT SKYBLUE (2950 2450);
FORCEPROP 1 LAST WATTAGE 1/16W
J 2
(2925 2450);
DISPLAY 0.617021 (2925 2450);
PAINT SKYBLUE (2925 2450);
FORCEPROP 1 LAST TOLERANCE 1%
J 0
(2950 2500);
DISPLAY 0.617021 (2950 2500);
PAINT SKYBLUE (2950 2500);
FORCEPROP 1 LAST VALUE 33.2
J 2
(2925 2500);
DISPLAY 0.617021 (2925 2500);
PAINT SKYBLUE (2925 2500);
FORCEPROP 1 LAST LOCATION R1L29
J 0
(2900 2650);
DISPLAY 0.617021 (2900 2650);
PAINT AQUA (2900 2650);
FORCEPROP 1 LAST PATH I68
J 0
(2900 2750);
DISPLAY 0.978723 (2900 2750);
PAINT WHITE (2900 2750);
DISPLAY INVISIBLE (2900 2750);
FORCEPROP 2 LAST CDS_LOCATION R1L29
J 0
(2900 2650);
DISPLAY 0.617021 (2900 2650);
PAINT AQUA (2900 2650);
DISPLAY INVISIBLE (2900 2650);
FORCEPROP 2 LAST CDS_LIB mstr_discrete
J 0
(2950 2600);
PAINT MONO (2950 2600);
DISPLAY INVISIBLE (2950 2600);
FORCEPROP 2 LAST SEC 1
J 0
(2900 2800);
PAINT MONO (2900 2800);
DISPLAY INVISIBLE (2900 2800);
FORCEPROP 2 LAST SEC_TYPE 0402
J 0
(2900 2800);
DISPLAY 1.021277 (2900 2800);
PAINT ORANGE (2900 2800);
DISPLAY INVISIBLE (2900 2800);
FORCEPROP 2 LAST ROOM M-SATA
J 0
(3125 2700);
DISPLAY 1.404255 (3125 2700);
PAINT ORANGE (3125 2700);
DISPLAY INVISIBLE (3125 2700);
FORCEADD P1V05_PCH_STBY..1
(-850 650);
FORCEPROP 3 LASTPIN (-850 600) SIG_NAME P1V05_PCH_STBY\g
J 0
(-840 610);
DISPLAY 0.659574 (-840 610);
PAINT MONO (-840 610);
DISPLAY INVISIBLE (-840 610);
FORCEPROP 1 LAST PATH I69
J 0
(-800 675);
DISPLAY 0.872340 (-800 675);
PAINT AQUA (-800 675);
DISPLAY INVISIBLE (-800 675);
FORCEPROP 2 LAST CDS_LIB mstr_symbols
J 0
(-850 650);
PAINT ORANGE (-850 650);
DISPLAY INVISIBLE (-850 650);
FORCEPROP 1 LAST VOLTAGE 1.05V
J 0
(-895 607);
DISPLAY 0.340426 (-895 607);
PAINT SKYBLUE (-895 607);
DISPLAY INVISIBLE (-895 607);
FORCEPROP 1 LAST BODY_TYPE PLUMBING
J 0
(-895 607);
DISPLAY 0.340426 (-895 607);
PAINT GREEN (-895 607);
DISPLAY INVISIBLE (-895 607);
FORCEPROP 1 LAST HDL_POWER P1V05_PCH_STBY
J 0
(-850 700);
DISPLAY 0.872340 (-850 700);
PAINT GREEN (-850 700);
DISPLAY INVISIBLE (-850 700);
FORCEADD GND..1
(3075 1825);
FORCEPROP 3 LASTPIN (3075 1875) SIG_NAME GND\g
J 0
(3085 1885);
DISPLAY 0.659574 (3085 1885);
PAINT MONO (3085 1885);
DISPLAY INVISIBLE (3085 1885);
FORCEPROP 2 LAST ROOM CPU_XDP_DEBUG
J 0
(2625 1900);
DISPLAY 1.617021 (2625 1900);
PAINT WHITE (2625 1900);
DISPLAY INVISIBLE (2625 1900);
FORCEPROP 1 LAST VOLTAGE 0.0V
J 0
(3030 1782);
DISPLAY 0.340426 (3030 1782);
PAINT SKYBLUE (3030 1782);
DISPLAY INVISIBLE (3030 1782);
FORCEPROP 2 LAST BOM_COST DEBUG
J 0
(2925 1900);
DISPLAY 1.617021 (2925 1900);
PAINT WHITE (2925 1900);
DISPLAY INVISIBLE (2925 1900);
FORCEPROP 1 LAST SIZE 1B
J 0
(3150 1775);
DISPLAY 1.893617 (3150 1775);
PAINT GREEN (3150 1775);
DISPLAY INVISIBLE (3150 1775);
FORCEPROP 1 LAST PATH I7
J 0
(3150 1825);
DISPLAY 0.872340 (3150 1825);
PAINT AQUA (3150 1825);
DISPLAY INVISIBLE (3150 1825);
FORCEPROP 2 LAST CDS_LIB mstr_symbols
J 0
(3075 1825);
DISPLAY 2.212766 (3075 1825);
PAINT ORANGE (3075 1825);
DISPLAY INVISIBLE (3075 1825);
FORCEPROP 1 LAST BODY_TYPE PLUMBING
J 0
(3030 1782);
DISPLAY 0.340426 (3030 1782);
PAINT GREEN (3030 1782);
DISPLAY INVISIBLE (3030 1782);
FORCEPROP 1 LAST HDL_POWER GND
J 0
(3075 1975);
PAINT GREEN (3075 1975);
DISPLAY INVISIBLE (3075 1975);
FORCEADD P1V05_PCH_STBY..1
(750 4750);
FORCEPROP 3 LASTPIN (750 4700) SIG_NAME P1V05_PCH_STBY\g
J 0
(760 4710);
DISPLAY 0.659574 (760 4710);
PAINT MONO (760 4710);
DISPLAY INVISIBLE (760 4710);
FORCEPROP 1 LAST PATH I70
J 0
(800 4775);
DISPLAY 0.872340 (800 4775);
PAINT AQUA (800 4775);
DISPLAY INVISIBLE (800 4775);
FORCEPROP 2 LAST CDS_LIB mstr_symbols
J 0
(750 4750);
PAINT ORANGE (750 4750);
DISPLAY INVISIBLE (750 4750);
FORCEPROP 1 LAST VOLTAGE 1.05V
J 0
(705 4707);
DISPLAY 0.340426 (705 4707);
PAINT SKYBLUE (705 4707);
DISPLAY INVISIBLE (705 4707);
FORCEPROP 1 LAST BODY_TYPE PLUMBING
J 0
(705 4707);
DISPLAY 0.340426 (705 4707);
PAINT GREEN (705 4707);
DISPLAY INVISIBLE (705 4707);
FORCEPROP 1 LAST HDL_POWER P1V05_PCH_STBY
J 0
(750 4800);
DISPLAY 0.872340 (750 4800);
PAINT GREEN (750 4800);
DISPLAY INVISIBLE (750 4800);
FORCEADD P1V05_PCH_STBY..1
(0 4750);
FORCEPROP 3 LASTPIN (0 4700) SIG_NAME P1V05_PCH_STBY\g
J 0
(10 4710);
DISPLAY 0.659574 (10 4710);
PAINT MONO (10 4710);
DISPLAY INVISIBLE (10 4710);
FORCEPROP 1 LAST VOLTAGE 1.05V
J 0
(-45 4707);
DISPLAY 0.340426 (-45 4707);
PAINT SKYBLUE (-45 4707);
DISPLAY INVISIBLE (-45 4707);
FORCEPROP 2 LAST CDS_LIB mstr_symbols
J 0
(0 4750);
PAINT ORANGE (0 4750);
DISPLAY INVISIBLE (0 4750);
FORCEPROP 1 LAST PATH I71
J 0
(50 4775);
DISPLAY 0.872340 (50 4775);
PAINT AQUA (50 4775);
DISPLAY INVISIBLE (50 4775);
FORCEPROP 1 LAST BODY_TYPE PLUMBING
J 0
(-45 4707);
DISPLAY 0.340426 (-45 4707);
PAINT GREEN (-45 4707);
DISPLAY INVISIBLE (-45 4707);
FORCEPROP 1 LAST HDL_POWER P1V05_PCH_STBY
J 0
(0 4800);
DISPLAY 0.872340 (0 4800);
PAINT GREEN (0 4800);
DISPLAY INVISIBLE (0 4800);
FORCEADD RES..1
(-1900 3100);
FORCEPROP 1 LAST PART_NUMBER G21497-005
J 0
(-1975 3025);
DISPLAY 0.617021 (-1975 3025);
PAINT BLUE (-1975 3025);
FORCEPROP 1 LAST MATERIAL CHIP
J 0
(-1550 3125);
DISPLAY 0.617021 (-1550 3125);
PAINT SKYBLUE (-1550 3125);
FORCEPROP 1 LAST WATTAGE 1/16W
J 2
(-2100 3125);
DISPLAY 0.617021 (-2100 3125);
PAINT SKYBLUE (-2100 3125);
FORCEPROP 1 LAST VALUE 0.0
J 2
(-2000 3125);
DISPLAY 0.617021 (-2000 3125);
PAINT SKYBLUE (-2000 3125);
FORCEPROP 1 LASTPIN (-2000 3100) $PN 1
J 0
(-1988 3112);
DISPLAY 0.617021 (-1988 3112);
PAINT ORANGE (-1988 3112);
FORCEPROP 1 LASTPIN (-1800 3100) $PN 2
J 0
(-1838 3112);
DISPLAY 0.617021 (-1838 3112);
PAINT ORANGE (-1838 3112);
FORCEPROP 1 LAST TOLERANCE 5%
J 0
(-1750 3125);
DISPLAY 0.617021 (-1750 3125);
PAINT SKYBLUE (-1750 3125);
FORCEPROP 1 LAST LOCATION R9A3
J 0
(-1950 3150);
DISPLAY 0.617021 (-1950 3150);
PAINT AQUA (-1950 3150);
FORCEPROP 1 LAST PACK_TYPE 0402
J 0
(-1650 3125);
DISPLAY 0.617021 (-1650 3125);
PAINT SKYBLUE (-1650 3125);
FORCEPROP 0 LAST ROOM DEBUG
J 0
(-1950 3300);
DISPLAY 1.021277 (-1950 3300);
PAINT ORANGE (-1950 3300);
DISPLAY INVISIBLE (-1950 3300);
FORCEPROP 1 LAST PATH I74
J 0
(-1950 3250);
DISPLAY 0.978723 (-1950 3250);
PAINT WHITE (-1950 3250);
DISPLAY INVISIBLE (-1950 3250);
FORCEPROP 2 LAST SEC 1
J 0
(-1950 3300);
DISPLAY 0.680851 (-1950 3300);
PAINT MONO (-1950 3300);
DISPLAY INVISIBLE (-1950 3300);
FORCEPROP 2 LAST SEC_TYPE 0402
J 0
(-1950 3300);
DISPLAY 1.021277 (-1950 3300);
PAINT ORANGE (-1950 3300);
DISPLAY INVISIBLE (-1950 3300);
FORCEPROP 2 LAST CDS_LIB mstr_discrete
J 0
(-1900 3100);
PAINT MONO (-1900 3100);
DISPLAY INVISIBLE (-1900 3100);
FORCEPROP 2 LAST CDS_LOCATION R9A3
J 0
(-1950 3150);
DISPLAY 0.617021 (-1950 3150);
PAINT AQUA (-1950 3150);
DISPLAY INVISIBLE (-1950 3150);
FORCEADD OFFPAGE..1
(-3250 3100);
FORCEPROP 2 LAST $XR1 112 
J 0
(-3622 3100);
DISPLAY 0.638298 (-3622 3100);
PAINT MONO (-3622 3100);
FORCEPROP 2 LAST $XR0 118 
J 0
(-3502 3100);
DISPLAY 0.638298 (-3502 3100);
PAINT MONO (-3502 3100);
FORCEPROP 2 LAST BOM_COST DEBUG
J 0
(-3450 3150);
DISPLAY 1.617021 (-3450 3150);
PAINT WHITE (-3450 3150);
DISPLAY INVISIBLE (-3450 3150);
FORCEPROP 2 LAST ROOM CPU_XDP_DEBUG
J 0
(-3450 3150);
DISPLAY 1.617021 (-3450 3150);
PAINT WHITE (-3450 3150);
DISPLAY INVISIBLE (-3450 3150);
FORCEPROP 2 LAST PATH I75
J 0
(-3200 3175);
DISPLAY 1.021277 (-3200 3175);
PAINT ORANGE (-3200 3175);
DISPLAY INVISIBLE (-3200 3175);
FORCEPROP 2 LAST CDS_LIB mstr_standard
J 0
(-3250 3100);
PAINT MONO (-3250 3100);
DISPLAY INVISIBLE (-3250 3100);
FORCEPROP 1 LAST OFFPAGE TRUE
J 0
(-2925 2975);
PAINT GREEN (-2925 2975);
DISPLAY INVISIBLE (-2925 2975);
FORCEPROP 1 LAST COMMENT_BODY TRUE
J 0
(-3125 3000);
DISPLAY 1.893617 (-3125 3000);
PAINT PEACH (-3125 3000);
DISPLAY INVISIBLE (-3125 3000);
FORCEADD GND..1
(3100 1375);
FORCEPROP 3 LASTPIN (3100 1425) SIG_NAME GND\g
J 0
(3110 1435);
DISPLAY 0.659574 (3110 1435);
PAINT MONO (3110 1435);
DISPLAY INVISIBLE (3110 1435);
FORCEPROP 2 LAST ROOM CPU_XDP_DEBUG
J 0
(2650 1450);
DISPLAY 1.617021 (2650 1450);
PAINT WHITE (2650 1450);
DISPLAY INVISIBLE (2650 1450);
FORCEPROP 1 LAST VOLTAGE 0.0V
J 0
(3055 1332);
DISPLAY 0.340426 (3055 1332);
PAINT SKYBLUE (3055 1332);
DISPLAY INVISIBLE (3055 1332);
FORCEPROP 2 LAST BOM_COST DEBUG
J 0
(2950 1450);
DISPLAY 1.617021 (2950 1450);
PAINT WHITE (2950 1450);
DISPLAY INVISIBLE (2950 1450);
FORCEPROP 2 LAST CDS_LIB mstr_symbols
J 0
(3100 1375);
DISPLAY 2.212766 (3100 1375);
PAINT ORANGE (3100 1375);
DISPLAY INVISIBLE (3100 1375);
FORCEPROP 1 LAST SIZE 1B
J 0
(3175 1325);
DISPLAY 1.893617 (3175 1325);
PAINT GREEN (3175 1325);
DISPLAY INVISIBLE (3175 1325);
FORCEPROP 1 LAST PATH I8
J 0
(3175 1375);
DISPLAY 0.872340 (3175 1375);
PAINT AQUA (3175 1375);
DISPLAY INVISIBLE (3175 1375);
FORCEPROP 1 LAST BODY_TYPE PLUMBING
J 0
(3055 1332);
DISPLAY 0.340426 (3055 1332);
PAINT GREEN (3055 1332);
DISPLAY INVISIBLE (3055 1332);
FORCEPROP 1 LAST HDL_POWER GND
J 0
(3100 1525);
PAINT GREEN (3100 1525);
DISPLAY INVISIBLE (3100 1525);
FORCEADD RES..2
(-2925 2675);
FORCEPROP 1 LASTPIN (-2925 2575) $PN 2
J 0
(-2920 2585);
DISPLAY 0.617021 (-2920 2585);
PAINT ORANGE (-2920 2585);
FORCEPROP 1 LASTPIN (-2925 2775) $PN 1
J 0
(-2920 2737);
DISPLAY 0.617021 (-2920 2737);
PAINT ORANGE (-2920 2737);
FORCEPROP 1 LAST LOCATION R9A2
J 0
(-2780 2800);
DISPLAY 0.617021 (-2780 2800);
PAINT AQUA (-2780 2800);
FORCEPROP 1 LAST VALUE 33.2
J 0
(-2780 2750);
DISPLAY 0.617021 (-2780 2750);
PAINT SKYBLUE (-2780 2750);
FORCEPROP 1 LAST TOLERANCE 1%
J 0
(-2780 2700);
DISPLAY 0.617021 (-2780 2700);
PAINT SKYBLUE (-2780 2700);
FORCEPROP 1 LAST WATTAGE 1/16W
J 0
(-2785 2650);
DISPLAY 0.617021 (-2785 2650);
PAINT SKYBLUE (-2785 2650);
FORCEPROP 1 LAST MATERIAL EMPTY
J 0
(-2785 2600);
DISPLAY 0.617021 (-2785 2600);
PAINT RED (-2785 2600);
FORCEPROP 1 LAST PART_NUMBER G21796-074
J 0
(-2785 2550);
DISPLAY 0.617021 (-2785 2550);
PAINT BLUE (-2785 2550);
FORCEPROP 1 LAST PACK_TYPE 0402
J 0
(-2785 2500);
DISPLAY 0.617021 (-2785 2500);
PAINT SKYBLUE (-2785 2500);
FORCEPROP 2 LAST CDS_LIB mstr_discrete
J 0
(-2925 2675);
PAINT ORANGE (-2925 2675);
DISPLAY INVISIBLE (-2925 2675);
FORCEPROP 2 LAST CDS_LOCATION R9A2
J 0
(-2880 2800);
DISPLAY 0.617021 (-2880 2800);
PAINT AQUA (-2880 2800);
DISPLAY INVISIBLE (-2880 2800);
FORCEPROP 0 LAST ROOM DEBUG
J 0
(-2875 2900);
DISPLAY 1.021277 (-2875 2900);
PAINT ORANGE (-2875 2900);
DISPLAY INVISIBLE (-2875 2900);
FORCEPROP 2 LAST SEC_TYPE 0402
J 0
(-2875 2900);
DISPLAY 1.021277 (-2875 2900);
PAINT ORANGE (-2875 2900);
DISPLAY INVISIBLE (-2875 2900);
FORCEPROP 2 LAST SEC 1
J 0
(-2875 2900);
DISPLAY 0.680851 (-2875 2900);
PAINT MONO (-2875 2900);
DISPLAY INVISIBLE (-2875 2900);
FORCEPROP 1 LAST PATH I83
J 0
(-2875 2850);
DISPLAY 0.978723 (-2875 2850);
PAINT WHITE (-2875 2850);
DISPLAY INVISIBLE (-2875 2850);
FORCEADD TTL1G07_A..1
(1775 2600);
FORCEPROP 1 LAST LOCATION U1L4
J 0
(1725 2800);
DISPLAY 0.617021 (1725 2800);
PAINT AQUA (1725 2800);
FORCEPROP 1 LAST MATERIAL IC
J 0
(1725 2750);
DISPLAY 0.617021 (1725 2750);
PAINT SKYBLUE (1725 2750);
FORCEPROP 2 LASTPIN (1675 2600) $PN 2
J 2
(1665 2610);
DISPLAY 0.617021 (1665 2610);
PAINT ORANGE (1665 2610);
FORCEPROP 2 LASTPIN (1925 2600) $PN 4
J 0
(1935 2610);
DISPLAY 0.617021 (1935 2610);
PAINT ORANGE (1935 2610);
FORCEPROP 1 LAST VALUE 74LVC1G07
J 1
(1775 2700);
DISPLAY 0.617021 (1775 2700);
PAINT SKYBLUE (1775 2700);
FORCEPROP 1 LAST PART_NUMBER C88419-001
J 0
(1725 2465);
DISPLAY 0.617021 (1725 2465);
PAINT BLUE (1725 2465);
FORCEPROP 1 LAST POWER_GROUP VCC=P3V3_STBY;GND=GND
J 1
(1725 2410);
DISPLAY 0.617021 (1725 2410);
PAINT ORANGE (1725 2410);
FORCEPROP 0 LAST ROOM M-SATA
J 0
(1725 2900);
DISPLAY 1.021277 (1725 2900);
PAINT ORANGE (1725 2900);
DISPLAY INVISIBLE (1725 2900);
FORCEPROP 0 LAST BOM_COST M-SATA
J 0
(1725 3000);
DISPLAY 1.021277 (1725 3000);
PAINT ORANGE (1725 3000);
DISPLAY INVISIBLE (1725 3000);
FORCEPROP 2 LAST SEC_TYPE SOP
J 0
(1725 2850);
DISPLAY 1.021277 (1725 2850);
PAINT ORANGE (1725 2850);
DISPLAY INVISIBLE (1725 2850);
FORCEPROP 2 LAST SEC 1
J 0
(1725 2850);
DISPLAY 0.680851 (1725 2850);
PAINT MONO (1725 2850);
DISPLAY INVISIBLE (1725 2850);
FORCEPROP 2 LAST CDS_LOCATION U1L4
J 0
(1725 2800);
DISPLAY 0.617021 (1725 2800);
PAINT AQUA (1725 2800);
DISPLAY INVISIBLE (1725 2800);
FORCEPROP 2 LAST CDS_LIB mstr_ttl
J 0
(1775 2600);
PAINT ORANGE (1775 2600);
DISPLAY INVISIBLE (1775 2600);
FORCEPROP 1 LAST PACK_TYPE SOP
J 0
(1725 2850);
DISPLAY 0.978723 (1725 2850);
PAINT SKYBLUE (1725 2850);
DISPLAY INVISIBLE (1725 2850);
FORCEPROP 1 LAST PATH I85
J 0
(1825 2650);
DISPLAY 0.978723 (1825 2650);
PAINT WHITE (1825 2650);
DISPLAY INVISIBLE (1825 2650);
FORCEADD P3V3_STBY..1
(3900 3925);
FORCEPROP 3 LASTPIN (3900 3875) SIG_NAME P3V3_STBY\g
J 0
(3910 3885);
DISPLAY 0.659574 (3910 3885);
PAINT MONO (3910 3885);
DISPLAY INVISIBLE (3910 3885);
FORCEPROP 1 LAST VOLTAGE 3.3V
J 0
(3855 3882);
DISPLAY 0.340426 (3855 3882);
PAINT SKYBLUE (3855 3882);
DISPLAY INVISIBLE (3855 3882);
FORCEPROP 2 LAST CDS_LIB mstr_symbols
J 0
(3900 3925);
PAINT ORANGE (3900 3925);
DISPLAY INVISIBLE (3900 3925);
FORCEPROP 1 LAST SIZE 1B
J 0
(3945 3947);
DISPLAY 0.340426 (3945 3947);
PAINT GREEN (3945 3947);
DISPLAY INVISIBLE (3945 3947);
FORCEPROP 1 LAST PATH I86
J 0
(3945 3927);
DISPLAY 0.340426 (3945 3927);
PAINT GREEN (3945 3927);
DISPLAY INVISIBLE (3945 3927);
FORCEPROP 1 LAST BODY_TYPE PLUMBING
J 0
(3855 3882);
DISPLAY 0.340426 (3855 3882);
PAINT GREEN (3855 3882);
DISPLAY INVISIBLE (3855 3882);
FORCEPROP 1 LAST HDL_POWER P3V3_STBY
J 0
(3600 3800);
DISPLAY 0.872340 (3600 3800);
PAINT ORANGE (3600 3800);
DISPLAY INVISIBLE (3600 3800);
FORCEADD CAP_A..1
(3900 3625);
FORCEPROP 1 LASTPIN (3900 3725) $PN 1
J 0
(3910 3705);
DISPLAY 0.617021 (3910 3705);
PAINT ORANGE (3910 3705);
FORCEPROP 1 LASTPIN (3900 3525) $PN 2
J 0
(3910 3505);
DISPLAY 0.617021 (3910 3505);
PAINT ORANGE (3910 3505);
FORCEPROP 1 LAST MATERIAL X7R
J 0
(3950 3525);
DISPLAY 0.617021 (3950 3525);
PAINT SKYBLUE (3950 3525);
FORCEPROP 1 LAST PACK_TYPE 0402V
J 0
(3950 3425);
DISPLAY 0.617021 (3950 3425);
PAINT SKYBLUE (3950 3425);
FORCEPROP 1 LAST TOLERANCE 10%
J 0
(3950 3575);
DISPLAY 0.617021 (3950 3575);
PAINT SKYBLUE (3950 3575);
FORCEPROP 1 LAST LOCATION C1L11
J 0
(3950 3725);
DISPLAY 0.617021 (3950 3725);
PAINT AQUA (3950 3725);
FORCEPROP 1 LAST VOLTAGE 16V
J 0
(3950 3625);
DISPLAY 0.617021 (3950 3625);
PAINT SKYBLUE (3950 3625);
FORCEPROP 1 LAST VALUE 0.1UF
J 0
(3950 3675);
DISPLAY 0.617021 (3950 3675);
PAINT SKYBLUE (3950 3675);
FORCEPROP 1 LAST PART_NUMBER A36096-030
J 0
(3950 3475);
DISPLAY 0.617021 (3950 3475);
PAINT BLUE (3950 3475);
FORCEPROP 2 LAST ROOM DEBUG
J 0
(3950 3775);
DISPLAY 1.021277 (3950 3775);
PAINT ORANGE (3950 3775);
DISPLAY INVISIBLE (3950 3775);
FORCEPROP 2 LAST CDS_LIB dev_discrete
J 0
(3900 3625);
PAINT ORANGE (3900 3625);
DISPLAY INVISIBLE (3900 3625);
FORCEPROP 2 LAST CDS_SEC 1
J 0
(3950 3775);
PAINT ORANGE (3950 3775);
DISPLAY INVISIBLE (3950 3775);
FORCEPROP 1 LAST PATH I87
J 0
(3950 3775);
DISPLAY 0.978723 (3950 3775);
PAINT WHITE (3950 3775);
DISPLAY INVISIBLE (3950 3775);
FORCEPROP 2 LAST CDS_LOCATION C1L11
J 0
(3950 3725);
DISPLAY 0.617021 (3950 3725);
PAINT AQUA (3950 3725);
DISPLAY INVISIBLE (3950 3725);
FORCEPROP 2 LAST SEC 1
J 0
(3950 3775);
DISPLAY 0.680851 (3950 3775);
PAINT MONO (3950 3775);
DISPLAY INVISIBLE (3950 3775);
FORCEPROP 2 LAST SEC_TYPE 0402V
J 0
(3950 3825);
DISPLAY 1.021277 (3950 3825);
PAINT ORANGE (3950 3825);
DISPLAY INVISIBLE (3950 3825);
FORCEPROP 2 LAST BOM_COST DEBUG
J 0
(3950 3825);
DISPLAY 1.021277 (3950 3825);
PAINT ORANGE (3950 3825);
DISPLAY INVISIBLE (3950 3825);
FORCEADD GND..1
(3900 3325);
FORCEPROP 3 LASTPIN (3900 3375) SIG_NAME GND\g
J 0
(3910 3385);
DISPLAY 0.659574 (3910 3385);
PAINT MONO (3910 3385);
DISPLAY INVISIBLE (3910 3385);
FORCEPROP 1 LAST VOLTAGE 0.0V
J 0
(3855 3282);
DISPLAY 0.340426 (3855 3282);
PAINT SKYBLUE (3855 3282);
DISPLAY INVISIBLE (3855 3282);
FORCEPROP 1 LAST SIZE 1B
J 0
(3975 3275);
DISPLAY 0.872340 (3975 3275);
PAINT AQUA (3975 3275);
DISPLAY INVISIBLE (3975 3275);
FORCEPROP 2 LAST CDS_LIB mstr_symbols
J 0
(3900 3325);
PAINT ORANGE (3900 3325);
DISPLAY INVISIBLE (3900 3325);
FORCEPROP 1 LAST PATH I88
J 0
(3975 3325);
DISPLAY 0.872340 (3975 3325);
PAINT AQUA (3975 3325);
DISPLAY INVISIBLE (3975 3325);
FORCEPROP 1 LAST BODY_TYPE PLUMBING
J 0
(3855 3282);
DISPLAY 0.340426 (3855 3282);
PAINT GREEN (3855 3282);
DISPLAY INVISIBLE (3855 3282);
FORCEPROP 1 LAST HDL_POWER GND
J 0
(3900 3475);
DISPLAY 0.872340 (3900 3475);
PAINT GREEN (3900 3475);
DISPLAY INVISIBLE (3900 3475);
FORCEADD RES..1
(2050 4550);
FORCEPROP 1 LAST PACK_TYPE 0402
J 0
(2300 4400);
DISPLAY 0.617021 (2300 4400);
PAINT SKYBLUE (2300 4400);
FORCEPROP 1 LASTPIN (2150 4550) $PN 2
J 0
(2112 4562);
DISPLAY 0.617021 (2112 4562);
PAINT ORANGE (2112 4562);
FORCEPROP 1 LAST PART_NUMBER G21796-026
J 0
(2000 4650);
DISPLAY 0.617021 (2000 4650);
PAINT BLUE (2000 4650);
FORCEPROP 1 LAST LOCATION R8E2
J 0
(2000 4600);
DISPLAY 0.617021 (2000 4600);
PAINT AQUA (2000 4600);
FORCEPROP 1 LASTPIN (1950 4550) $PN 1
J 0
(1962 4562);
DISPLAY 0.617021 (1962 4562);
PAINT ORANGE (1962 4562);
FORCEPROP 1 LAST VALUE 1.00K
J 2
(2025 4450);
DISPLAY 0.617021 (2025 4450);
PAINT SKYBLUE (2025 4450);
FORCEPROP 1 LAST WATTAGE 1/16W
J 2
(2025 4400);
DISPLAY 0.617021 (2025 4400);
PAINT SKYBLUE (2025 4400);
FORCEPROP 1 LAST MATERIAL CHIP
J 0
(2050 4400);
DISPLAY 0.617021 (2050 4400);
PAINT SKYBLUE (2050 4400);
FORCEPROP 1 LAST TOLERANCE 1%
J 0
(2050 4450);
DISPLAY 0.617021 (2050 4450);
PAINT SKYBLUE (2050 4450);
FORCEPROP 2 LAST CDS_LOCATION R8E2
J 0
(2000 4600);
DISPLAY 0.617021 (2000 4600);
PAINT AQUA (2000 4600);
DISPLAY INVISIBLE (2000 4600);
FORCEPROP 2 LAST ROOM DEBUG
J 0
(2000 4700);
DISPLAY 1.617021 (2000 4700);
PAINT WHITE (2000 4700);
DISPLAY INVISIBLE (2000 4700);
FORCEPROP 2 LAST BOM_COST DEBUG
J 0
(2000 4650);
DISPLAY 1.617021 (2000 4650);
PAINT WHITE (2000 4650);
DISPLAY INVISIBLE (2000 4650);
FORCEPROP 2 LAST SEC_TYPE 0402
J 0
(2000 4750);
DISPLAY 1.021277 (2000 4750);
PAINT ORANGE (2000 4750);
DISPLAY INVISIBLE (2000 4750);
FORCEPROP 2 LAST SEC 1
J 0
(2000 4750);
DISPLAY 0.680851 (2000 4750);
PAINT MONO (2000 4750);
DISPLAY INVISIBLE (2000 4750);
FORCEPROP 1 LAST PATH I89
J 0
(2000 4700);
DISPLAY 0.978723 (2000 4700);
PAINT WHITE (2000 4700);
DISPLAY INVISIBLE (2000 4700);
FORCEPROP 2 LAST CDS_LIB mstr_discrete
J 0
(2050 4550);
PAINT ORANGE (2050 4550);
DISPLAY INVISIBLE (2050 4550);
FORCEADD GND..1
(3125 875);
FORCEPROP 3 LASTPIN (3125 925) SIG_NAME GND\g
J 0
(3135 935);
DISPLAY 0.659574 (3135 935);
PAINT MONO (3135 935);
DISPLAY INVISIBLE (3135 935);
FORCEPROP 1 LAST SIZE 1B
J 0
(3200 825);
DISPLAY 1.893617 (3200 825);
PAINT GREEN (3200 825);
DISPLAY INVISIBLE (3200 825);
FORCEPROP 1 LAST PATH I9
J 0
(3200 875);
DISPLAY 0.872340 (3200 875);
PAINT AQUA (3200 875);
DISPLAY INVISIBLE (3200 875);
FORCEPROP 1 LAST VOLTAGE 0.0V
J 0
(3080 832);
DISPLAY 0.340426 (3080 832);
PAINT SKYBLUE (3080 832);
DISPLAY INVISIBLE (3080 832);
FORCEPROP 2 LAST CDS_LIB mstr_symbols
J 0
(3125 875);
DISPLAY 2.212766 (3125 875);
PAINT ORANGE (3125 875);
DISPLAY INVISIBLE (3125 875);
FORCEPROP 2 LAST BOM_COST DEBUG
J 0
(2975 950);
DISPLAY 1.617021 (2975 950);
PAINT WHITE (2975 950);
DISPLAY INVISIBLE (2975 950);
FORCEPROP 2 LAST ROOM CPU_XDP_DEBUG
J 0
(2675 950);
DISPLAY 1.617021 (2675 950);
PAINT WHITE (2675 950);
DISPLAY INVISIBLE (2675 950);
FORCEPROP 1 LAST BODY_TYPE PLUMBING
J 0
(3080 832);
DISPLAY 0.340426 (3080 832);
PAINT GREEN (3080 832);
DISPLAY INVISIBLE (3080 832);
FORCEPROP 1 LAST HDL_POWER GND
J 0
(3125 1025);
PAINT GREEN (3125 1025);
DISPLAY INVISIBLE (3125 1025);
FORCEADD OFFPAGE..2
(2975 4550);
FORCEPROP 2 LAST $XR3 184 
J 0
(3524 4550);
DISPLAY 0.638298 (3524 4550);
PAINT MONO (3524 4550);
FORCEPROP 2 LAST $XR2 154 
J 0
(3404 4550);
DISPLAY 0.638298 (3404 4550);
PAINT MONO (3404 4550);
FORCEPROP 2 LAST $XR1 125 
J 0
(3284 4550);
DISPLAY 0.638298 (3284 4550);
PAINT MONO (3284 4550);
FORCEPROP 2 LAST $XR0 121 
J 0
(3164 4550);
DISPLAY 0.638298 (3164 4550);
PAINT MONO (3164 4550);
FORCEPROP 2 LAST CDS_LIB mstr_standard
J 0
(2975 4550);
PAINT ORANGE (2975 4550);
DISPLAY INVISIBLE (2975 4550);
FORCEPROP 2 LAST BOM_COST DEBUG
J 0
(3350 4600);
DISPLAY 1.617021 (3350 4600);
PAINT WHITE (3350 4600);
DISPLAY INVISIBLE (3350 4600);
FORCEPROP 2 LAST ROOM CPU_XDP_DEBUG
J 0
(3350 4600);
DISPLAY 1.617021 (3350 4600);
PAINT WHITE (3350 4600);
DISPLAY INVISIBLE (3350 4600);
FORCEPROP 2 LAST PATH I90
J 0
(3150 4625);
DISPLAY 1.021277 (3150 4625);
PAINT ORANGE (3150 4625);
DISPLAY INVISIBLE (3150 4625);
FORCEPROP 1 LAST OFFPAGE TRUE
J 0
(3300 4425);
PAINT GREEN (3300 4425);
DISPLAY INVISIBLE (3300 4425);
FORCEPROP 1 LAST COMMENT_BODY TRUE
J 0
(2930 4455);
DISPLAY 1.893617 (2930 4455);
PAINT PEACH (2930 4455);
DISPLAY INVISIBLE (2930 4455);
FORCEADD OFFPAGE..3
(1875 4150);
FORCEPROP 2 LAST $XR0 112 
J 0
(2089 4150);
DISPLAY 0.638298 (2089 4150);
PAINT MONO (2089 4150);
FORCEPROP 2 LAST CDS_LIB mstr_standard
J 0
(1875 4150);
PAINT ORANGE (1875 4150);
DISPLAY INVISIBLE (1875 4150);
FORCEPROP 2 LAST BOM_COST DEBUG
J 0
(2250 4200);
DISPLAY 1.617021 (2250 4200);
PAINT WHITE (2250 4200);
DISPLAY INVISIBLE (2250 4200);
FORCEPROP 2 LAST ROOM CPU_XDP_DEBUG
J 0
(2250 4200);
DISPLAY 1.617021 (2250 4200);
PAINT WHITE (2250 4200);
DISPLAY INVISIBLE (2250 4200);
FORCEPROP 2 LAST PATH I91
J 0
(2050 4225);
DISPLAY 1.021277 (2050 4225);
PAINT ORANGE (2050 4225);
DISPLAY INVISIBLE (2050 4225);
FORCEPROP 1 LAST OFFPAGE TRUE
J 0
(2200 4025);
DISPLAY 0.872340 (2200 4025);
PAINT GREEN (2200 4025);
DISPLAY INVISIBLE (2200 4025);
FORCEPROP 1 LAST COMMENT_BODY TRUE
J 0
(1825 4050);
DISPLAY 0.872340 (1825 4050);
PAINT GREEN (1825 4050);
DISPLAY INVISIBLE (1825 4050);
FORCEADD OFFPAGE..3
(1875 4100);
FORCEPROP 2 LAST $XR0 112 
J 0
(2089 4100);
DISPLAY 0.638298 (2089 4100);
PAINT MONO (2089 4100);
FORCEPROP 2 LAST CDS_LIB mstr_standard
J 0
(1875 4100);
PAINT ORANGE (1875 4100);
DISPLAY INVISIBLE (1875 4100);
FORCEPROP 2 LAST BOM_COST DEBUG
J 0
(2250 4150);
DISPLAY 1.617021 (2250 4150);
PAINT WHITE (2250 4150);
DISPLAY INVISIBLE (2250 4150);
FORCEPROP 2 LAST ROOM CPU_XDP_DEBUG
J 0
(2250 4150);
DISPLAY 1.617021 (2250 4150);
PAINT WHITE (2250 4150);
DISPLAY INVISIBLE (2250 4150);
FORCEPROP 2 LAST PATH I92
J 0
(2050 4175);
DISPLAY 1.021277 (2050 4175);
PAINT ORANGE (2050 4175);
DISPLAY INVISIBLE (2050 4175);
FORCEPROP 1 LAST OFFPAGE TRUE
J 0
(2200 3975);
DISPLAY 0.872340 (2200 3975);
PAINT GREEN (2200 3975);
DISPLAY INVISIBLE (2200 3975);
FORCEPROP 1 LAST COMMENT_BODY TRUE
J 0
(1825 4000);
DISPLAY 0.872340 (1825 4000);
PAINT GREEN (1825 4000);
DISPLAY INVISIBLE (1825 4000);
FORCEADD NPN_DUAL..2
(-2150 2325);
FORCEPROP 1 LASTPIN (-2150 2425) $PN 2
J 0
(-2145 2410);
DISPLAY 0.617021 (-2145 2410);
PAINT AQUA (-2145 2410);
FORCEPROP 1 LAST PART_NUMBER C52264-001
J 0
(-2250 2150);
DISPLAY 0.617021 (-2250 2150);
PAINT BLUE (-2250 2150);
FORCEPROP 1 LAST LOCATION Q9A1
J 0
(-2275 2400);
DISPLAY 0.617021 (-2275 2400);
PAINT AQUA (-2275 2400);
FORCEPROP 1 LASTPIN (-2250 2275) $PN 1
J 2
(-2250 2285);
DISPLAY 0.617021 (-2250 2285);
PAINT AQUA (-2250 2285);
FORCEPROP 1 LAST VALUE MBT3904
J 0
(-2100 2425);
DISPLAY 0.617021 (-2100 2425);
PAINT SKYBLUE (-2100 2425);
FORCEPROP 1 LAST MATERIAL EMPTY
J 0
(-2050 2350);
DISPLAY 0.617021 (-2050 2350);
PAINT RED (-2050 2350);
FORCEPROP 1 LASTPIN (-2050 2275) $PN 6
J 0
(-2015 2285);
DISPLAY 0.617021 (-2015 2285);
PAINT AQUA (-2015 2285);
FORCEPROP 1 LAST PATH I93
J 0
(-1725 2400);
DISPLAY 0.978723 (-1725 2400);
PAINT BLUE (-1725 2400);
DISPLAY INVISIBLE (-1725 2400);
FORCEPROP 0 LAST ROOM DEBUG
J 0
(-2050 2550);
DISPLAY 1.021277 (-2050 2550);
PAINT ORANGE (-2050 2550);
DISPLAY INVISIBLE (-2050 2550);
FORCEPROP 2 LAST SEC 2
J 0
(-2050 2500);
DISPLAY 0.680851 (-2050 2500);
PAINT MONO (-2050 2500);
DISPLAY INVISIBLE (-2050 2500);
FORCEPROP 2 LAST SEC_TYPE SSOPLF
J 0
(-2050 2500);
DISPLAY 1.021277 (-2050 2500);
PAINT ORANGE (-2050 2500);
DISPLAY INVISIBLE (-2050 2500);
FORCEPROP 1 LAST PACK_TYPE SSOPLF
J 0
(-2050 2500);
DISPLAY 0.978723 (-2050 2500);
PAINT SKYBLUE (-2050 2500);
DISPLAY INVISIBLE (-2050 2500);
FORCEPROP 2 LAST CDS_LIB mstr_discrete
J 0
(-2150 2325);
PAINT ORANGE (-2150 2325);
DISPLAY INVISIBLE (-2150 2325);
FORCEPROP 2 LAST CDS_LOCATION Q9A1
J 0
(-2275 2400);
DISPLAY 0.617021 (-2275 2400);
PAINT AQUA (-2275 2400);
DISPLAY INVISIBLE (-2275 2400);
FORCEADD NPN_DUAL..1
(-1150 2275);
FORCEPROP 1 LAST LOCATION Q9A1
J 0
(-1225 2400);
DISPLAY 0.617021 (-1225 2400);
PAINT AQUA (-1225 2400);
FORCEPROP 1 LASTPIN (-1100 2375) $PN 3
J 0
(-1085 2385);
DISPLAY 0.617021 (-1085 2385);
PAINT AQUA (-1085 2385);
FORCEPROP 1 LAST VALUE MBT3904
J 0
(-975 2275);
DISPLAY 0.617021 (-975 2275);
PAINT SKYBLUE (-975 2275);
FORCEPROP 1 LASTPIN (-1100 2175) $PN 4
J 2
(-1060 2125);
DISPLAY 0.617021 (-1060 2125);
PAINT AQUA (-1060 2125);
FORCEPROP 1 LAST PART_NUMBER C52264-001
J 0
(-1025 2175);
DISPLAY 0.617021 (-1025 2175);
PAINT BLUE (-1025 2175);
FORCEPROP 1 LAST MATERIAL EMPTY
J 0
(-975 2225);
DISPLAY 0.617021 (-975 2225);
PAINT RED (-975 2225);
FORCEPROP 1 LASTPIN (-1250 2275) $PN 5
J 0
(-1260 2330);
DISPLAY 0.617021 (-1260 2330);
PAINT AQUA (-1260 2330);
FORCEPROP 2 LAST CDS_LIB mstr_discrete
J 0
(-1150 2275);
PAINT ORANGE (-1150 2275);
DISPLAY INVISIBLE (-1150 2275);
FORCEPROP 2 LAST CDS_LOCATION Q9A1
J 0
(-1225 2400);
DISPLAY 0.617021 (-1225 2400);
PAINT AQUA (-1225 2400);
DISPLAY INVISIBLE (-1225 2400);
FORCEPROP 1 LAST PACK_TYPE SSOPLF
J 0
(-1050 2425);
DISPLAY 0.978723 (-1050 2425);
PAINT SKYBLUE (-1050 2425);
DISPLAY INVISIBLE (-1050 2425);
FORCEPROP 2 LAST SEC 1
J 0
(-1050 2425);
DISPLAY 0.680851 (-1050 2425);
PAINT MONO (-1050 2425);
DISPLAY INVISIBLE (-1050 2425);
FORCEPROP 2 LAST SEC_TYPE SSOPLF
J 0
(-1050 2425);
DISPLAY 1.021277 (-1050 2425);
PAINT ORANGE (-1050 2425);
DISPLAY INVISIBLE (-1050 2425);
FORCEPROP 0 LAST ROOM DEBUG
J 0
(-1050 2475);
DISPLAY 1.021277 (-1050 2475);
PAINT ORANGE (-1050 2475);
DISPLAY INVISIBLE (-1050 2475);
FORCEPROP 1 LAST PATH I94
J 0
(-650 2275);
DISPLAY 0.978723 (-650 2275);
PAINT BLUE (-650 2275);
DISPLAY INVISIBLE (-650 2275);
FORCEADD RES..2
R 2
(-1850 2700);
FORCEPROP 1 LAST VALUE 1.00K
J 2
(-1920 2750);
DISPLAY 0.617021 (-1920 2750);
PAINT SKYBLUE (-1920 2750);
FORCEPROP 1 LAST LOCATION R9A1
J 2
(-1670 2675);
DISPLAY 0.617021 (-1670 2675);
PAINT AQUA (-1670 2675);
FORCEPROP 1 LAST MATERIAL EMPTY
J 2
(-1615 2750);
DISPLAY 0.617021 (-1615 2750);
PAINT RED (-1615 2750);
FORCEPROP 1 LASTPIN (-1850 2800) $PN 1
J 2
(-1855 2762);
DISPLAY 0.617021 (-1855 2762);
PAINT ORANGE (-1855 2762);
FORCEPROP 1 LAST TOLERANCE 1%
J 2
(-1970 2650);
DISPLAY 0.617021 (-1970 2650);
PAINT SKYBLUE (-1970 2650);
FORCEPROP 1 LAST WATTAGE 1/16W
J 2
(-1940 2700);
DISPLAY 0.617021 (-1940 2700);
PAINT SKYBLUE (-1940 2700);
FORCEPROP 1 LAST PART_NUMBER G21796-026
J 2
(-1990 2600);
DISPLAY 0.617021 (-1990 2600);
PAINT BLUE (-1990 2600);
FORCEPROP 1 LASTPIN (-1850 2600) $PN 2
J 2
(-1855 2610);
DISPLAY 0.617021 (-1855 2610);
PAINT ORANGE (-1855 2610);
FORCEPROP 1 LAST PACK_TYPE 0402
J 2
(-1890 2575);
DISPLAY 0.617021 (-1890 2575);
PAINT SKYBLUE (-1890 2575);
FORCEPROP 2 LAST CDS_LIB mstr_discrete
J 0
(-1850 2700);
PAINT ORANGE (-1850 2700);
DISPLAY INVISIBLE (-1850 2700);
FORCEPROP 0 LAST ROOM DEBUG
J 2
(-1875 2825);
DISPLAY 1.021277 (-1875 2825);
PAINT ORANGE (-1875 2825);
DISPLAY INVISIBLE (-1875 2825);
FORCEPROP 1 LAST PATH I95
J 2
(-1900 2875);
DISPLAY 0.978723 (-1900 2875);
PAINT WHITE (-1900 2875);
DISPLAY INVISIBLE (-1900 2875);
FORCEPROP 2 LAST SEC 1
J 0
(-1900 2925);
DISPLAY 0.680851 (-1900 2925);
PAINT MONO (-1900 2925);
DISPLAY INVISIBLE (-1900 2925);
FORCEPROP 2 LAST SEC_TYPE 0402
J 0
(-1900 2925);
DISPLAY 1.021277 (-1900 2925);
PAINT ORANGE (-1900 2925);
DISPLAY INVISIBLE (-1900 2925);
FORCEPROP 2 LAST CDS_LOCATION R9A1
J 2
(-1670 2675);
DISPLAY 0.617021 (-1670 2675);
PAINT AQUA (-1670 2675);
DISPLAY INVISIBLE (-1670 2675);
FORCEADD P3V3..1
(-1850 2950);
FORCEPROP 3 LASTPIN (-1850 2900) SIG_NAME P3V3\g
J 0
(-1840 2910);
DISPLAY 0.659574 (-1840 2910);
PAINT MONO (-1840 2910);
DISPLAY INVISIBLE (-1840 2910);
FORCEPROP 1 LAST VOLTAGE 3.3V
J 0
(-1895 2907);
DISPLAY 0.340426 (-1895 2907);
PAINT SKYBLUE (-1895 2907);
DISPLAY INVISIBLE (-1895 2907);
FORCEPROP 2 LAST CDS_LIB mstr_symbols
J 0
(-1850 2950);
PAINT ORANGE (-1850 2950);
DISPLAY INVISIBLE (-1850 2950);
FORCEPROP 1 LAST SIZE 1B
J 0
(-1805 2972);
DISPLAY 0.340426 (-1805 2972);
PAINT GREEN (-1805 2972);
DISPLAY INVISIBLE (-1805 2972);
FORCEPROP 1 LAST PATH I96
J 0
(-1805 2952);
DISPLAY 0.340426 (-1805 2952);
PAINT GREEN (-1805 2952);
DISPLAY INVISIBLE (-1805 2952);
FORCEPROP 1 LAST BODY_TYPE PLUMBING
J 0
(-1895 2907);
DISPLAY 0.340426 (-1895 2907);
PAINT GREEN (-1895 2907);
DISPLAY INVISIBLE (-1895 2907);
FORCEPROP 1 LAST HDL_POWER P3V3
J 0
(-2175 2825);
DISPLAY 0.872340 (-2175 2825);
PAINT ORANGE (-2175 2825);
DISPLAY INVISIBLE (-2175 2825);
FORCEADD RES..2
(2175 2800);
FORCEPROP 1 LAST PACK_TYPE 0402
J 0
(2215 2625);
DISPLAY 0.617021 (2215 2625);
PAINT SKYBLUE (2215 2625);
FORCEPROP 1 LAST MATERIAL EMPTY
J 0
(2215 2725);
DISPLAY 0.617021 (2215 2725);
PAINT RED (2215 2725);
FORCEPROP 1 LAST TOLERANCE 1%
J 0
(2220 2825);
DISPLAY 0.617021 (2220 2825);
PAINT SKYBLUE (2220 2825);
FORCEPROP 1 LAST WATTAGE 1/16W
J 0
(2215 2775);
DISPLAY 0.617021 (2215 2775);
PAINT SKYBLUE (2215 2775);
FORCEPROP 1 LASTPIN (2175 2700) $PN 2
J 0
(2180 2710);
DISPLAY 0.787234 (2180 2710);
PAINT ORANGE (2180 2710);
FORCEPROP 1 LASTPIN (2175 2900) $PN 1
J 0
(2180 2862);
DISPLAY 0.787234 (2180 2862);
PAINT ORANGE (2180 2862);
FORCEPROP 1 LAST VALUE 4.75K
J 0
(2220 2875);
DISPLAY 0.617021 (2220 2875);
PAINT SKYBLUE (2220 2875);
FORCEPROP 1 LAST LOCATION R1L28
J 0
(2220 2925);
DISPLAY 0.617021 (2220 2925);
PAINT AQUA (2220 2925);
FORCEPROP 1 LAST PART_NUMBER G21796-072
J 0
(2215 2675);
DISPLAY 0.617021 (2215 2675);
PAINT BLUE (2215 2675);
FORCEPROP 2 LAST SEC_TYPE 0402
J 0
(2225 3025);
DISPLAY 1.021277 (2225 3025);
PAINT ORANGE (2225 3025);
DISPLAY INVISIBLE (2225 3025);
FORCEPROP 2 LAST SEC 1
J 0
(2225 3025);
DISPLAY 0.680851 (2225 3025);
PAINT MONO (2225 3025);
DISPLAY INVISIBLE (2225 3025);
FORCEPROP 2 LAST CDS_LIB mstr_discrete
J 0
(2175 2800);
PAINT MONO (2175 2800);
DISPLAY INVISIBLE (2175 2800);
FORCEPROP 1 LAST PATH I97
J 0
(2225 2975);
DISPLAY 0.978723 (2225 2975);
PAINT WHITE (2225 2975);
DISPLAY INVISIBLE (2225 2975);
FORCEPROP 2 LAST ROOM MIO_CHASSIS
J 0
(2225 2975);
DISPLAY 1.021277 (2225 2975);
PAINT ORANGE (2225 2975);
DISPLAY INVISIBLE (2225 2975);
FORCEPROP 2 LAST BOM_COST MIO_CHASSIS
J 0
(2225 3025);
DISPLAY 1.021277 (2225 3025);
PAINT ORANGE (2225 3025);
DISPLAY INVISIBLE (2225 3025);
FORCEADD CAD_NOTE..1
(-2200 2075);
FORCEPROP 0 LAST L1 PLACE BUFFER CIRCUITRY WITHIN 1.1'' OF XDP CONN
J 0
(-3375 1925);
DISPLAY 1.170213 (-3375 1925);
PAINT WHITE (-3375 1925);
FORCEPROP 2 LAST CDS_LIB mstr_symbols
J 0
(-2200 2075);
PAINT MONO (-2200 2075);
DISPLAY INVISIBLE (-2200 2075);
FORCEPROP 1 LAST COMMENT_BODY TRUE
J 0
(-2175 2175);
DISPLAY 2.212766 (-2175 2175);
PAINT PEACH (-2175 2175);
DISPLAY INVISIBLE (-2175 2175);
FORCEADD DNS..2
(-2920 2670);
PAINT RED (-2920 2670);
FORCEPROP 2 LAST CDS_LIB mstr_misc
J 0
(-2920 2670);
PAINT ORANGE (-2920 2670);
DISPLAY INVISIBLE (-2920 2670);
FORCEPROP 1 LAST COMMENT_BODY TRUE
R 1
J 0
(-2845 2445);
DISPLAY 0.872340 (-2845 2445);
PAINT GREEN (-2845 2445);
DISPLAY INVISIBLE (-2845 2445);
FORCEADD DNS..2
(-1845 2695);
PAINT RED (-1845 2695);
FORCEPROP 2 LAST CDS_LIB mstr_misc
J 0
(-1845 2695);
PAINT ORANGE (-1845 2695);
DISPLAY INVISIBLE (-1845 2695);
FORCEPROP 1 LAST COMMENT_BODY TRUE
R 1
J 0
(-1770 2470);
DISPLAY 0.872340 (-1770 2470);
PAINT GREEN (-1770 2470);
DISPLAY INVISIBLE (-1770 2470);
FORCEADD CAD_NOTE..1
(2875 4900);
FORCEPROP 0 LAST L1 PLACE XDP SERIES R CLSOE TO
J 2
(3125 4775);
DISPLAY 0.638298 (3125 4775);
PAINT ORANGE (3125 4775);
FORCEPROP 0 LAST L2 T POINT WHERE IT CONNECTS TO SPI
J 2
(3125 4700);
DISPLAY 0.638298 (3125 4700);
PAINT ORANGE (3125 4700);
FORCEPROP 2 LAST CDS_LIB mstr_symbols
J 0
(2875 4900);
PAINT ORANGE (2875 4900);
DISPLAY INVISIBLE (2875 4900);
FORCEPROP 1 LAST COMMENT_BODY TRUE
J 0
(2900 5000);
DISPLAY 0.978723 (2900 5000);
PAINT ORANGE (2900 5000);
DISPLAY INVISIBLE (2900 5000);
FORCEADD DNS..2
(-1145 2270);
PAINT RED (-1145 2270);
FORCEPROP 2 LAST CDS_LIB mstr_misc
J 0
(-1145 2270);
PAINT ORANGE (-1145 2270);
DISPLAY INVISIBLE (-1145 2270);
FORCEPROP 1 LAST COMMENT_BODY TRUE
R 1
J 0
(-1070 2045);
DISPLAY 0.872340 (-1070 2045);
PAINT GREEN (-1070 2045);
DISPLAY INVISIBLE (-1070 2045);
FORCEADD DNS..2
(2180 2820);
PAINT RED (2180 2820);
FORCEPROP 2 LAST CDS_LIB mstr_misc
J 0
(2180 2820);
PAINT MONO (2180 2820);
DISPLAY INVISIBLE (2180 2820);
FORCEPROP 1 LAST COMMENT_BODY TRUE
R 1
J 0
(2255 2595);
DISPLAY 0.872340 (2255 2595);
PAINT GREEN (2255 2595);
DISPLAY INVISIBLE (2255 2595);
FORCEADD CAD_NOTE..1
(-2300 4975);
FORCEPROP 0 LAST L1 PLACE XDP SERIES R CLSOE TO
J 2
(-2050 4850);
DISPLAY 0.638298 (-2050 4850);
PAINT ORANGE (-2050 4850);
FORCEPROP 0 LAST L2 T POINT WHERE IT CONNECTS TO SPI
J 2
(-2050 4775);
DISPLAY 0.638298 (-2050 4775);
PAINT ORANGE (-2050 4775);
FORCEPROP 2 LAST CDS_LIB mstr_symbols
J 0
(-2300 4975);
PAINT ORANGE (-2300 4975);
DISPLAY INVISIBLE (-2300 4975);
FORCEPROP 1 LAST COMMENT_BODY TRUE
J 0
(-2275 5075);
DISPLAY 0.978723 (-2275 5075);
PAINT ORANGE (-2275 5075);
DISPLAY INVISIBLE (-2275 5075);
FORCEADD DNS..2
(-2145 2345);
PAINT RED (-2145 2345);
FORCEPROP 2 LAST CDS_LIB mstr_misc
J 0
(-2145 2345);
PAINT ORANGE (-2145 2345);
DISPLAY INVISIBLE (-2145 2345);
FORCEPROP 1 LAST COMMENT_BODY TRUE
R 1
J 0
(-2070 2120);
DISPLAY 0.872340 (-2070 2120);
PAINT GREEN (-2070 2120);
DISPLAY INVISIBLE (-2070 2120);
FORCEADD CAD_NOTE..1
(3500 3775);
FORCEPROP 0 LAST L1 PLACE 0.1UF CAP NEXT TO VCC PIN
J 2
(3750 3650);
DISPLAY 1.021277 (3750 3650);
PAINT ORANGE (3750 3650);
FORCEPROP 0 LAST L2 ON TTL1G07_A
J 2
(3750 3575);
DISPLAY 1.021277 (3750 3575);
PAINT ORANGE (3750 3575);
FORCEPROP 2 LAST CDS_LIB mstr_symbols
J 0
(3500 3775);
PAINT ORANGE (3500 3775);
DISPLAY INVISIBLE (3500 3775);
FORCEPROP 1 LAST COMMENT_BODY TRUE
J 0
(3525 3875);
DISPLAY 0.978723 (3525 3875);
PAINT ORANGE (3525 3875);
DISPLAY INVISIBLE (3525 3875);
FORCEADD INTEL_CORP_BPAGE..1
(4250 200);
FORCEPROP 1 LAST CDS_CON_LAST_MODIFIED Fri Jun 16 17:48:44 2017
J 0
(2825 525);
PAINT ORANGE (2825 525);
DISPLAY INVISIBLE (2825 525);
FORCEPROP 1 LAST CUSTOM_TXT_CDS <CURRENT_DESIGN_SHEET> OF <TOTAL_DESIGN_SHEETS>
J 0
(3750 225);
PAINT ORANGE (3750 225);
FORCEPROP 1 LAST CUSTOM_TXT_CDS <CON_LAST_MODIFIED>
J 0
(250 300);
PAINT ORANGE (250 300);
FORCEPROP 2 LAST CUSTOM_TXT_CDS <XR_PAGE_TITLE>
J 0
(-3640 5450);
DISPLAY 0.638298 (-3640 5450);
PAINT PINK (-3640 5450);
DISPLAY INVISIBLE (-3640 5450);
FORCEPROP 1 LAST SCH_TITLE CPU & PCH XDP (1-2)
J 0
(-3700 250);
DISPLAY 1.212766 (-3700 250);
PAINT YELLOW (-3700 250);
FORCEPROP 2 LAST PAGE_BORDER TRUE
J 0
(-3640 5450);
DISPLAY 0.638298 (-3640 5450);
PAINT PINK (-3640 5450);
DISPLAY INVISIBLE (-3640 5450);
FORCEPROP 2 LAST CDS_LIB mstr_symbols
J 0
(4250 200);
PAINT MONO (4250 200);
DISPLAY INVISIBLE (4250 200);
FORCEPROP 1 LAST COMMENT_BODY TRUE
J 0
(4262 212);
DISPLAY 0.468085 (4262 212);
PAINT PEACH (4262 212);
DISPLAY INVISIBLE (4262 212);
FORCEPROP 2 LAST CDS_XR_PAGE_TITLE CR-111 : @BASEBOARD_FAB2_LIB.BASEBOARD_FAB2(SCH_1):PAGE111
J 0
(-3640 5450);
DISPLAY 0.638298 (-3640 5450);
PAINT PINK (-3640 5450);
DISPLAY INVISIBLE (-3640 5450);
WIRE 16 -1 (875 2775)(875 2675);
WIRE 16 -1 (875 3450)(875 2775);
WIRE 16 -1 (750 2775)(875 2775);
WIRE 16 -1 (750 2825)(750 2775);
WIRE 16 -1 (875 3750)(875 3450);
WIRE 16 -1 (500 3450)(875 3450);
WIRE 16 -1 (875 3900)(875 3750);
WIRE 16 -1 (500 3750)(875 3750);
WIRE 16 -1 (875 4050)(875 3900);
WIRE 16 -1 (500 3900)(875 3900);
WIRE 16 -1 (875 4200)(875 4050);
WIRE 16 -1 (500 4050)(875 4050);
WIRE 16 -1 (875 4200)(875 4350);
WIRE 16 -1 (500 4200)(875 4200);
WIRE 16 -1 (875 4500)(875 4350);
WIRE 16 -1 (500 4350)(875 4350);
WIRE 16 -1 (875 4650)(875 4500);
WIRE 16 -1 (500 4500)(875 4500);
WIRE 16 -1 (500 4650)(875 4650);
WIRE 16 -1 (-100 2675)(-100 2775);
WIRE 16 -1 (-100 2775)(-100 3200);
WIRE 16 -1 (0 2775)(-100 2775);
WIRE 16 -1 (0 2825)(0 2775);
WIRE 16 -1 (-100 3450)(-100 3200);
WIRE 16 -1 (200 3200)(-100 3200);
WIRE 16 -1 (-100 3750)(-100 3450);
WIRE 16 -1 (200 3450)(-100 3450);
WIRE 16 -1 (-100 3900)(-100 3750);
WIRE 16 -1 (200 3750)(-100 3750);
WIRE 16 -1 (-100 4050)(-100 3900);
WIRE 16 -1 (200 3900)(-100 3900);
WIRE 16 -1 (-100 4200)(-100 4050);
WIRE 16 -1 (200 4050)(-100 4050);
WIRE 16 -1 (-100 4350)(-100 4200);
WIRE 16 -1 (200 4200)(-100 4200);
WIRE 16 -1 (-100 4500)(-100 4350);
WIRE 16 -1 (200 4350)(-100 4350);
WIRE 16 -1 (200 4500)(-100 4500);
WIRE 16 -1 (-850 1550)(-850 1450);
WIRE 16 -1 (-850 1100)(-850 1450);
WIRE 16 -1 (-1300 1450)(-850 1450);
WIRE 16 -1 (-1300 1100)(-850 1100);
WIRE 16 -1 (-1100 850)(-1100 875);
WIRE 16 -1 (-1300 875)(-1100 875);
WIRE 16 -1 (3250 2150)(3250 2250);
WIRE 16 -1 (3250 2150)(3250 1700);
WIRE 16 -1 (2825 2150)(3250 2150);
WIRE 16 -1 (3250 1150)(3250 1700);
WIRE 16 -1 (2825 1700)(3250 1700);
WIRE 16 -1 (2825 1150)(3250 1150);
WIRE 16 -1 (2175 2900)(2175 2925);
WIRE 16 -1 (-850 600)(-850 500);
WIRE 16 -1 (-1300 500)(-850 500);
WIRE 16 -1 (3075 1875)(3075 1900);
WIRE 16 -1 (2850 1900)(3075 1900);
WIRE 16 -1 (750 4700)(750 3600);
WIRE 16 -1 (500 3600)(750 3600);
WIRE 16 -1 (750 3025)(750 3600);
WIRE 16 -1 (0 4700)(0 3600);
WIRE 16 -1 (200 3600)(0 3600);
WIRE 16 -1 (0 3600)(0 3025);
WIRE 16 -1 (3100 1425)(3100 1450);
WIRE 16 -1 (2900 1450)(3100 1450);
WIRE 16 -1 (3900 3875)(3900 3725);
WIRE 16 -1 (3900 3375)(3900 3525);
WIRE 16 -1 (3125 925)(3125 950);
WIRE 16 -1 (2925 950)(3125 950);
WIRE 16 -1 (-1850 2850)(-1850 2900);
WIRE 16 -1 (-1100 2850)(-1850 2850);
WIRE 16 -1 (-1850 2800)(-1850 2850);
WIRE 16 -1 (-1100 2375)(-1100 2850);
WIRE 16 -1 (200 3700)(-2075 3700);
FORCEPROP 2 LAST SIG_NAME XDP_RSMRST_N
J 0
(-985 3710);
DISPLAY 0.617021 (-985 3710);
PAINT ORANGE (-985 3710);
FORCEPROP 2 LASTPROP $XRERR UNIQUE?
J 0
(-1225 3710);
DISPLAY 0.638298 (-1225 3710);
PAINT MONO (-1225 3710);
DISPLAY INVISIBLE (-1225 3710);
WIRE 16 -1 (3050 2600)(3525 2600);
FORCEPROP 2 LAST SIG_NAME FM_DEBUG_RST_BTN_N
J 0
(3090 2610);
DISPLAY 0.617021 (3090 2610);
PAINT ORANGE (3090 2610);
WIRE 16 -1 (1825 3950)(500 3950);
FORCEPROP 2 LAST SIG_NAME TP_XDP_CPU_OBSDATA_D1
J 0
(990 3960);
DISPLAY 0.617021 (990 3960);
PAINT ORANGE (990 3960);
FORCEPROP 2 LASTPROP $XRERR UNIQUE?
J 0
(1855 3950);
DISPLAY 0.638298 (1855 3950);
PAINT MONO (1855 3950);
DISPLAY INVISIBLE (1855 3950);
WIRE 16 -1 (1825 3850)(500 3850);
FORCEPROP 2 LAST SIG_NAME TP_XDP_CPU_OBSDATA_D2
J 0
(990 3860);
DISPLAY 0.617021 (990 3860);
PAINT ORANGE (990 3860);
FORCEPROP 2 LASTPROP $XRERR UNIQUE?
J 0
(1855 3850);
DISPLAY 0.638298 (1855 3850);
PAINT MONO (1855 3850);
DISPLAY INVISIBLE (1855 3850);
WIRE 16 -1 (-1125 4600)(200 4600);
FORCEPROP 2 LAST SIG_NAME XDP_PREQ_N
J 0
(-985 4610);
DISPLAY 0.617021 (-985 4610);
PAINT ORANGE (-985 4610);
WIRE 16 -1 (1825 3400)(500 3400);
FORCEPROP 2 LAST SIG_NAME XDP_TDO
J 0
(990 3410);
DISPLAY 0.617021 (990 3410);
PAINT ORANGE (990 3410);
WIRE 16 -1 (1825 3350)(500 3350);
FORCEPROP 2 LAST SIG_NAME XDP_TRST_N
J 0
(990 3360);
DISPLAY 0.617021 (990 3360);
PAINT ORANGE (990 3360);
WIRE 16 -1 (1825 3200)(500 3200);
FORCEPROP 2 LAST SIG_NAME XDP_PRESENT_N
J 0
(990 3210);
DISPLAY 0.617021 (990 3210);
PAINT ORANGE (990 3210);
WIRE 16 -1 (500 4550)(1950 4550);
FORCEPROP 2 LAST SIG_NAME XDP_SPI_PCH_MOSI_BOOT_HALT_N
J 0
(990 4560);
DISPLAY 0.617021 (990 4560);
PAINT ORANGE (990 4560);
FORCEPROP 2 LASTPROP $XRERR UNIQUE?
J 0
(750 4560);
DISPLAY 0.638298 (750 4560);
PAINT MONO (750 4560);
DISPLAY INVISIBLE (750 4560);
WIRE 16 -1 (1825 4400)(500 4400);
FORCEPROP 2 LAST SIG_NAME TP_XDP_CPU_OBSDATA_C1
J 0
(990 4410);
DISPLAY 0.617021 (990 4410);
PAINT ORANGE (990 4410);
FORCEPROP 2 LASTPROP $XRERR UNIQUE?
J 0
(1855 4400);
DISPLAY 0.638298 (1855 4400);
PAINT MONO (1855 4400);
DISPLAY INVISIBLE (1855 4400);
WIRE 16 -1 (1825 4450)(500 4450);
FORCEPROP 2 LAST SIG_NAME TP_XDP_CPU_OBSDATA_C0
J 0
(990 4460);
DISPLAY 0.617021 (990 4460);
PAINT ORANGE (990 4460);
FORCEPROP 2 LASTPROP $XRERR UNIQUE?
J 0
(1855 4450);
DISPLAY 0.638298 (1855 4450);
PAINT MONO (1855 4450);
DISPLAY INVISIBLE (1855 4450);
WIRE 16 -1 (1825 4300)(500 4300);
FORCEPROP 2 LAST SIG_NAME TP_XDP_CPU_OBSDATA_C2
J 0
(990 4310);
DISPLAY 0.617021 (990 4310);
PAINT ORANGE (990 4310);
FORCEPROP 2 LASTPROP $XRERR UNIQUE?
J 0
(1855 4300);
DISPLAY 0.638298 (1855 4300);
PAINT MONO (1855 4300);
DISPLAY INVISIBLE (1855 4300);
WIRE 16 -1 (2150 4550)(2925 4550);
FORCEPROP 0 LAST SIG_NAME SPI_PCH_MOSI
J 0
(2540 4560);
DISPLAY 0.617021 (2540 4560);
PAINT ORANGE (2540 4560);
WIRE 16 -1 (1825 4250)(500 4250);
FORCEPROP 2 LAST SIG_NAME TP_XDP_CPU_OBSDATA_C3
J 0
(990 4260);
DISPLAY 0.617021 (990 4260);
PAINT ORANGE (990 4260);
FORCEPROP 2 LASTPROP $XRERR UNIQUE?
J 0
(1855 4250);
DISPLAY 0.638298 (1855 4250);
PAINT MONO (1855 4250);
DISPLAY INVISIBLE (1855 4250);
WIRE 16 -1 (1825 3300)(500 3300);
FORCEPROP 2 LAST SIG_NAME XDP_TDI
J 0
(990 3310);
DISPLAY 0.617021 (990 3310);
PAINT ORANGE (990 3310);
WIRE 16 -1 (200 3950)(-1125 3950);
FORCEPROP 2 LAST SIG_NAME TP_XDP_OBSDATA_B1
J 0
(-985 3960);
DISPLAY 0.617021 (-985 3960);
PAINT ORANGE (-985 3960);
FORCEPROP 2 LASTPROP $XRERR UNIQUE?
J 0
(-1365 3950);
DISPLAY 0.638298 (-1365 3950);
PAINT MONO (-1365 3950);
DISPLAY INVISIBLE (-1365 3950);
WIRE 16 -1 (200 3300)(-1125 3300);
FORCEPROP 2 LAST SIG_NAME XDP_PCH_TCK1
J 0
(-985 3310);
DISPLAY 0.617021 (-985 3310);
PAINT ORANGE (-985 3310);
WIRE 16 -1 (200 3400)(-1125 3400);
FORCEPROP 2 LAST SIG_NAME SMB_HOST_STBY_LVC3_SDA
J 0
(-985 3410);
DISPLAY 0.617021 (-985 3410);
PAINT ORANGE (-985 3410);
WIRE 16 -1 (200 3350)(-1125 3350);
FORCEPROP 2 LAST SIG_NAME SMB_HOST_STBY_LVC3_SCL
J 0
(-985 3360);
DISPLAY 0.617021 (-985 3360);
PAINT ORANGE (-985 3360);
WIRE 16 -1 (200 3500)(-1125 3500);
FORCEPROP 2 LAST SIG_NAME XDP_SYSPWROK
J 0
(-985 3510);
DISPLAY 0.638298 (-985 3510);
PAINT ORANGE (-985 3510);
WIRE 16 -1 (200 3550)(-1125 3550);
FORCEPROP 2 LAST SIG_NAME XDP_CPU_PWR_DEBUG_N
J 0
(-985 3560);
DISPLAY 0.617021 (-985 3560);
PAINT ORANGE (-985 3560);
WIRE 16 -1 (200 3650)(-1125 3650);
FORCEPROP 2 LAST SIG_NAME XDP_PWRGD_RST_N
J 0
(-985 3660);
DISPLAY 0.617021 (-985 3660);
PAINT ORANGE (-985 3660);
WIRE 16 -1 (-1125 4550)(200 4550);
FORCEPROP 2 LAST SIG_NAME XDP_PRDY_N
J 0
(-985 4560);
DISPLAY 0.617021 (-985 4560);
PAINT ORANGE (-985 4560);
WIRE 16 -1 (-1125 4400)(200 4400);
FORCEPROP 2 LAST SIG_NAME TP_XDP_OBSDATA_A1
J 0
(-985 4410);
DISPLAY 0.617021 (-985 4410);
PAINT ORANGE (-985 4410);
FORCEPROP 2 LASTPROP $XRERR UNIQUE?
J 0
(-1365 4400);
DISPLAY 0.638298 (-1365 4400);
PAINT MONO (-1365 4400);
DISPLAY INVISIBLE (-1365 4400);
WIRE 16 -1 (200 4300)(-1125 4300);
FORCEPROP 2 LAST SIG_NAME TP_XDP_OBSDATA_A2
J 0
(-985 4310);
DISPLAY 0.617021 (-985 4310);
PAINT ORANGE (-985 4310);
FORCEPROP 2 LASTPROP $XRERR UNIQUE?
J 0
(-1365 4300);
DISPLAY 0.638298 (-1365 4300);
PAINT MONO (-1365 4300);
DISPLAY INVISIBLE (-1365 4300);
WIRE 16 -1 (-2000 4650)(200 4650);
FORCEPROP 2 LAST SIG_NAME XDP_DEBUG_CONSENT_N
J 0
(-835 4660);
DISPLAY 0.617021 (-835 4660);
PAINT ORANGE (-835 4660);
FORCEPROP 2 LASTPROP $XRERR UNIQUE?
J 0
(-1075 4660);
DISPLAY 0.638298 (-1075 4660);
PAINT MONO (-1075 4660);
DISPLAY INVISIBLE (-1075 4660);
WIRE 16 -1 (-2925 2575)(-2925 2275);
WIRE 16 -1 (-2925 2275)(-2250 2275);
FORCEPROP 0 LAST SIG_NAME XDP_CPU_GTL_TCK_R2
J 0
(-2835 2285);
DISPLAY 0.617021 (-2835 2285);
PAINT ORANGE (-2835 2285);
FORCEPROP 2 LASTPROP $XRERR UNIQUE?
J 0
(-3075 2285);
DISPLAY 0.638298 (-3075 2285);
PAINT MONO (-3075 2285);
DISPLAY INVISIBLE (-3075 2285);
WIRE 16 -1 (1825 4600)(500 4600);
FORCEPROP 2 LAST SIG_NAME TP_XDP_CPU_OBSFN_C0
J 0
(990 4610);
DISPLAY 0.617021 (990 4610);
PAINT ORANGE (990 4610);
FORCEPROP 2 LASTPROP $XRERR UNIQUE?
J 0
(1855 4600);
DISPLAY 0.638298 (1855 4600);
PAINT MONO (1855 4600);
DISPLAY INVISIBLE (1855 4600);
WIRE 16 -1 (200 4150)(-1125 4150);
FORCEPROP 0 LAST SIG_NAME TP_XDP_OBSFN_B0
J 0
(-985 4160);
DISPLAY 0.617021 (-985 4160);
PAINT ORANGE (-985 4160);
FORCEPROP 2 LASTPROP $XRERR UNIQUE?
J 0
(-1365 4150);
DISPLAY 0.638298 (-1365 4150);
PAINT MONO (-1365 4150);
DISPLAY INVISIBLE (-1365 4150);
WIRE 16 -1 (1825 4150)(500 4150);
FORCEPROP 2 LAST SIG_NAME XDP_OBSFN_B0_MBP6_N
J 0
(990 4160);
DISPLAY 0.617021 (990 4160);
PAINT ORANGE (990 4160);
WIRE 16 -1 (1825 4100)(500 4100);
FORCEPROP 2 LAST SIG_NAME XDP_OBSFN_B1_MBP7_N
J 0
(990 4110);
DISPLAY 0.617021 (990 4110);
PAINT ORANGE (990 4110);
WIRE 16 -1 (1825 4000)(500 4000);
FORCEPROP 2 LAST SIG_NAME TP_XDP_CPU_OBSDATA_D0
J 0
(990 4010);
DISPLAY 0.617021 (990 4010);
PAINT ORANGE (990 4010);
FORCEPROP 2 LASTPROP $XRERR UNIQUE?
J 0
(1855 4000);
DISPLAY 0.638298 (1855 4000);
PAINT MONO (1855 4000);
DISPLAY INVISIBLE (1855 4000);
WIRE 16 -1 (1825 3800)(500 3800);
FORCEPROP 2 LAST SIG_NAME TP_XDP_CPU_OBSDATA_D3
J 0
(990 3810);
DISPLAY 0.617021 (990 3810);
PAINT ORANGE (990 3810);
FORCEPROP 2 LASTPROP $XRERR UNIQUE?
J 0
(1855 3800);
DISPLAY 0.638298 (1855 3800);
PAINT MONO (1855 3800);
DISPLAY INVISIBLE (1855 3800);
WIRE 16 -1 (1825 3700)(500 3700);
FORCEPROP 2 LAST SIG_NAME CLK_100M_PCH_XDP_DP
J 0
(975 3701);
DISPLAY 0.617021 (975 3701);
PAINT ORANGE (975 3701);
WIRE 16 -1 (1825 3650)(500 3650);
FORCEPROP 2 LAST SIG_NAME CLK_100M_PCH_XDP_DN
J 0
(975 3651);
DISPLAY 0.617021 (975 3651);
PAINT ORANGE (975 3651);
WIRE 16 -1 (1675 2600)(1350 2600);
WIRE 16 -1 (1350 3500)(1350 2600);
WIRE 16 -1 (1350 3500)(2800 3500);
WIRE 16 -1 (500 3500)(1350 3500);
FORCEPROP 2 LAST SIG_NAME XDP_RST_CO_N
J 0
(990 3510);
DISPLAY 0.617021 (990 3510);
PAINT ORANGE (990 3510);
WIRE 16 -1 (1825 3550)(500 3550);
FORCEPROP 2 LAST SIG_NAME XDP_ITP_PMODE
J 0
(990 3560);
DISPLAY 0.617021 (990 3560);
PAINT ORANGE (990 3560);
WIRE 16 -1 (200 4000)(-1125 4000);
FORCEPROP 2 LAST SIG_NAME TP_XDP_OBSDATA_B0
J 0
(-985 4010);
DISPLAY 0.617021 (-985 4010);
PAINT ORANGE (-985 4010);
FORCEPROP 2 LASTPROP $XRERR UNIQUE?
J 0
(-1365 4000);
DISPLAY 0.638298 (-1365 4000);
PAINT MONO (-1365 4000);
DISPLAY INVISIBLE (-1365 4000);
WIRE 16 -1 (-1125 4250)(200 4250);
FORCEPROP 2 LAST SIG_NAME TP_XDP_OBSDATA_A3
J 0
(-985 4260);
DISPLAY 0.617021 (-985 4260);
PAINT ORANGE (-985 4260);
FORCEPROP 2 LASTPROP $XRERR UNIQUE?
J 0
(-1365 4250);
DISPLAY 0.638298 (-1365 4250);
PAINT MONO (-1365 4250);
DISPLAY INVISIBLE (-1365 4250);
WIRE 16 -1 (-3200 3100)(-2925 3100);
FORCEPROP 0 LAST SIG_NAME XDP_PCH_CPU_TCK0
J 0
(-2835 3110);
DISPLAY 0.617021 (-2835 3110);
PAINT ORANGE (-2835 3110);
WIRE 16 -1 (-2000 3100)(-2925 3100);
WIRE 16 -1 (-2925 2775)(-2925 3100);
WIRE 16 -1 (-2050 2275)(-1850 2275);
WIRE 16 -1 (-1250 2275)(-1850 2275);
FORCEPROP 0 LAST SIG_NAME XDP_CPU_TCK_BUF
J 0
(-1735 2285);
DISPLAY 0.617021 (-1735 2285);
PAINT ORANGE (-1735 2285);
FORCEPROP 2 LASTPROP $XRERR UNIQUE?
J 0
(-1975 2285);
DISPLAY 0.638298 (-1975 2285);
PAINT MONO (-1975 2285);
DISPLAY INVISIBLE (-1975 2285);
WIRE 16 -1 (-1850 2525)(-1850 2275);
WIRE 16 -1 (-1850 2525)(-1850 2600);
WIRE 16 -1 (-1850 2525)(-2150 2525);
WIRE 16 -1 (-2150 2425)(-2150 2525);
WIRE 16 -1 (-2550 500)(-1500 500);
FORCEPROP 2 LAST SIG_NAME XDP_ITP_PMODE
J 0
(-2485 510);
DISPLAY 0.617021 (-2485 510);
PAINT ORANGE (-2485 510);
WIRE 16 -1 (1800 1150)(2450 1150);
FORCEPROP 2 LAST SIG_NAME XDP_PWRGD_RST_N
J 0
(1865 1160);
DISPLAY 0.617021 (1865 1160);
PAINT ORANGE (1865 1160);
WIRE 16 -1 (2450 1150)(2625 1150);
WIRE 16 -1 (2450 950)(2450 1150);
WIRE 16 -1 (2725 950)(2450 950);
WIRE 16 -1 (2700 1450)(2425 1450);
WIRE 16 -1 (2425 1450)(2425 1700);
WIRE 16 -1 (2425 1700)(2625 1700);
WIRE 16 -1 (1800 1700)(2425 1700);
FORCEPROP 2 LAST SIG_NAME XDP_RST_CO_N
J 0
(1865 1710);
DISPLAY 0.617021 (1865 1710);
PAINT ORANGE (1865 1710);
WIRE 16 -1 (2650 1900)(2425 1900);
WIRE 16 -1 (1800 2150)(2425 2150);
FORCEPROP 2 LAST SIG_NAME XDP_SYSPWROK
J 0
(1865 2160);
DISPLAY 0.638298 (1865 2160);
PAINT ORANGE (1865 2160);
WIRE 16 -1 (2425 1900)(2425 2150);
WIRE 16 -1 (2425 2150)(2625 2150);
WIRE 3 273 (1975 3100)(1975 2375);
WIRE 3 273 (2350 3100)(1975 3100);
WIRE 3 273 (1975 2375)(2350 2375);
WIRE 3 273 (2350 2375)(2350 3100);
WIRE 16 -1 (200 4100)(-1125 4100);
FORCEPROP 0 LAST SIG_NAME TP_XDP_OBSFN_B1
J 0
(-985 4110);
DISPLAY 0.617021 (-985 4110);
PAINT ORANGE (-985 4110);
FORCEPROP 2 LASTPROP $XRERR UNIQUE?
J 0
(-1365 4100);
DISPLAY 0.638298 (-1365 4100);
PAINT MONO (-1365 4100);
DISPLAY INVISIBLE (-1365 4100);
WIRE 16 -1 (-2900 4650)(-2200 4650);
FORCEPROP 2 LAST SIG_NAME SPI_PCH_IO2
J 0
(-2835 4660);
DISPLAY 0.638298 (-2835 4660);
PAINT ORANGE (-2835 4660);
WIRE 16 -1 (1925 2600)(2175 2600);
WIRE 16 -1 (2175 2700)(2175 2600);
WIRE 16 -1 (2850 2600)(2175 2600);
FORCEPROP 2 LAST SIG_NAME FM_DEBUG_RST_BTN_R1_N
J 0
(2365 2610);
DISPLAY 0.617021 (2365 2610);
PAINT ORANGE (2365 2610);
FORCEPROP 2 LASTPROP $XRERR UNIQUE?
J 0
(2125 2610);
DISPLAY 0.638298 (2125 2610);
PAINT MONO (2125 2610);
DISPLAY INVISIBLE (2125 2610);
WIRE 16 -1 (-2550 1450)(-1500 1450);
FORCEPROP 2 LAST SIG_NAME CPU_XDP_PRESENT_N
J 0
(-2485 1460);
DISPLAY 0.617021 (-2485 1460);
PAINT ORANGE (-2485 1460);
WIRE 16 -1 (-2550 1100)(-1775 1100);
FORCEPROP 2 LAST SIG_NAME XDP_CPU_PWR_DEBUG_N
J 0
(-2485 1110);
DISPLAY 0.617021 (-2485 1110);
PAINT ORANGE (-2485 1110);
WIRE 16 -1 (-1775 1100)(-1500 1100);
WIRE 16 -1 (-1775 875)(-1775 1100);
WIRE 16 -1 (-1500 875)(-1775 875);
WIRE 16 -1 (200 3850)(-1125 3850);
FORCEPROP 2 LAST SIG_NAME TP_XDP_OBSDATA_B2
J 0
(-985 3860);
DISPLAY 0.617021 (-985 3860);
PAINT ORANGE (-985 3860);
FORCEPROP 2 LASTPROP $XRERR UNIQUE?
J 0
(-1365 3850);
DISPLAY 0.638298 (-1365 3850);
PAINT MONO (-1365 3850);
DISPLAY INVISIBLE (-1365 3850);
WIRE 16 -1 (200 3800)(-1125 3800);
FORCEPROP 2 LAST SIG_NAME TP_XDP_OBSDATA_B3
J 0
(-985 3810);
DISPLAY 0.617021 (-985 3810);
PAINT ORANGE (-985 3810);
FORCEPROP 2 LASTPROP $XRERR UNIQUE?
J 0
(-1365 3800);
DISPLAY 0.638298 (-1365 3800);
PAINT MONO (-1365 3800);
DISPLAY INVISIBLE (-1365 3800);
WIRE 16 -1 (-1100 2075)(-1100 2175);
WIRE 16 -1 (-550 3250)(-1125 3250);
FORCEPROP 2 LAST SIG_NAME XDP_CPU_TCK0
J 0
(-985 3260);
DISPLAY 0.617021 (-985 3260);
PAINT ORANGE (-985 3260);
WIRE 16 -1 (200 3250)(-550 3250);
WIRE 16 -1 (-550 3250)(-550 3100);
WIRE 16 -1 (-750 2075)(-1100 2075);
WIRE 16 -1 (-750 3100)(-750 2075);
WIRE 16 -1 (-550 3100)(-750 3100);
WIRE 16 -1 (-1800 3100)(-750 3100);
WIRE 16 -1 (-2275 3700)(-2900 3700);
FORCEPROP 2 LAST SIG_NAME RST_RSMRST_N
J 0
(-2835 3710);
DISPLAY 0.638298 (-2835 3710);
PAINT ORANGE (-2835 3710);
WIRE 16 -1 (200 4450)(-1125 4450);
FORCEPROP 2 LAST SIG_NAME TP_XDP_OBSDATA_A0
J 0
(-985 4460);
DISPLAY 0.617021 (-985 4460);
PAINT ORANGE (-985 4460);
FORCEPROP 2 LASTPROP $XRERR UNIQUE?
J 0
(-1365 4450);
DISPLAY 0.638298 (-1365 4450);
PAINT MONO (-1365 4450);
DISPLAY INVISIBLE (-1365 4450);
WIRE 16 -1 (1825 3250)(500 3250);
FORCEPROP 2 LAST SIG_NAME XDP_TMS
J 0
(990 3260);
DISPLAY 0.617021 (990 3260);
PAINT ORANGE (990 3260);
DOT 1 (3250 2150);
DOT 1 (-100 2775);
DOT 1 (-100 3450);
DOT 1 (-100 3200);
DOT 1 (0 3600);
DOT 1 (-100 3750);
DOT 1 (-100 3900);
DOT 1 (-100 4050);
DOT 1 (-100 4200);
DOT 1 (-100 4350);
DOT 1 (875 2775);
DOT 1 (875 3450);
DOT 1 (750 3600);
DOT 1 (875 3750);
DOT 1 (875 3900);
DOT 1 (875 4050);
DOT 1 (1350 3500);
DOT 1 (2425 1700);
DOT 1 (3250 1700);
DOT 1 (2175 2600);
DOT 1 (875 4350);
DOT 1 (875 4200);
DOT 1 (875 4500);
DOT 1 (2450 1150);
DOT 1 (2425 2150);
DOT 1 (-1775 1100);
DOT 1 (-850 1450);
DOT 1 (-750 3100);
DOT 1 (-550 3250);
DOT 1 (-1850 2850);
DOT 1 (-1850 2275);
DOT 1 (-1850 2525);
DOT 1 (-2925 3100);
FORCENOTE
TP FAB1 CHANGE TO NOPOP  FOR CONTROL BOM 0128
(2425 2975) 0;
DISPLAY LEFT (2425 2975);
DISPLAY 1.021277 (2425 2975);
PAINT RED (2425 2975);
FORCENOTE
TP FAB3 RECONNECT 0921
(-2525 1500) 0;
DISPLAY LEFT (-2525 1500);
DISPLAY 1.021277 (-2525 1500);
PAINT RED (-2525 1500);
FORCENOTE
(HOOK7)
(550 3514) 0;
DISPLAY LEFT (550 3514);
DISPLAY 0.936170 (550 3514);
PAINT PURPLE (550 3514);
FORCENOTE
ROOM=DEBUG
(-3652 579) 0;
DISPLAY LEFT (-3652 579);
PAINT PURPLE (-3652 579);
FORCENOTE
(HOOK3)
(-450 3514) 0;
DISPLAY LEFT (-450 3514);
DISPLAY 0.936170 (-450 3514);
PAINT PURPLE (-450 3514);
FORCENOTE
(HOOK6)
(550 3564) 0;
DISPLAY LEFT (550 3564);
DISPLAY 0.936170 (550 3564);
PAINT PURPLE (550 3564);
FORCENOTE
(HOOK4)
(550 3714) 0;
DISPLAY LEFT (550 3714);
DISPLAY 0.936170 (550 3714);
PAINT PURPLE (550 3714);
FORCENOTE
(HOOK5)
(550 3664) 0;
DISPLAY LEFT (550 3664);
DISPLAY 0.936170 (550 3664);
PAINT PURPLE (550 3664);
FORCENOTE
(HOOK2)
(-450 3564) 0;
DISPLAY LEFT (-450 3564);
DISPLAY 0.936170 (-450 3564);
PAINT PURPLE (-450 3564);
FORCENOTE
(HOOK1)
(-475 3664) 0;
DISPLAY LEFT (-475 3664);
DISPLAY 0.936170 (-475 3664);
PAINT PURPLE (-475 3664);
FORCENOTE
(HOOK0)
(-475 3714) 0;
DISPLAY LEFT (-475 3714);
DISPLAY 0.936170 (-475 3714);
PAINT PURPLE (-475 3714);
QUIT
